G04 ================== begin FILE IDENTIFICATION RECORD ==================*
G04 Layout Name:  15105-sa.brd*
G04 Film Name:    DP_REF_L6*
G04 File Format:  Gerber RS274X*
G04 File Origin:  Cadence Allegro 16.5-S056*
G04 Origin Date:  Wed Nov 16 02:02:42 2016*
G04 *
G04 Layer:  BOARD GEOMETRY/DP_REF_L6_TBL*
G04 Layer:  BOARD GEOMETRY/DP_REF_L6_L6*
G04 Layer:  BOARD GEOMETRY/PANEL_OUTLINE*
G04 *
G04 Offset:    (0.00 0.00)*
G04 Mirror:    No*
G04 Mode:      Positive*
G04 Rotation:  0*
G04 FullContactRelief:  No*
G04 UndefLineWidth:     6.00*
G04 ================== end FILE IDENTIFICATION RECORD ====================*
%FSLAX35Y35*MOIN*%
%IR0*IPPOS*OFA0.00000B0.00000*MIA0B0*SFA1.00000B1.00000*%
%ADD10C,.02*%
%ADD11C,.004*%
%ADD12C,.006*%
%ADD13C,.0055*%
G75*
%LPD*%
G75*
G54D10*
G01X1479970Y759338D02*
X2267470D01*
G01X1479970Y863288D02*
Y759338D01*
G01Y793988D02*
X2267470D01*
G01X1479970Y828638D02*
X2267470D01*
G01X1479970Y863288D02*
X2267470D01*
G01X1654970D02*
Y759338D01*
G01X1952470Y863288D02*
Y759338D01*
G01X2057470Y863288D02*
Y759338D01*
G01X2267470Y863288D02*
Y759338D01*
G54D11*
G01X55600Y217768D02*
Y212928D01*
G01X54400Y217270D02*
Y212928D01*
G01X52368Y221000D02*
X55600Y217768D01*
G01X51870Y219800D02*
X54400Y217270D01*
G01X46898Y221000D02*
X52368D01*
G01X46400Y219800D02*
X51870D01*
G01X38200Y229698D02*
X46898Y221000D01*
G01X37000Y229200D02*
X46400Y219800D01*
G01X38200Y243802D02*
Y229698D01*
G01X37000Y244300D02*
Y229200D01*
G01X31497Y228705D02*
Y245096D01*
G01X32697Y242529D02*
Y244598D01*
G01Y238629D02*
Y239829D01*
G01Y229203D02*
Y235929D01*
G01X39050Y221152D02*
X31497Y228705D01*
G01X40250Y221650D02*
X32697Y229203D01*
G01X39050Y217728D02*
Y221152D01*
G01X40250Y217728D02*
Y221650D01*
G01X54400Y217270D02*
Y212928D01*
G01X55600Y217768D02*
Y212928D01*
G01X51870Y219800D02*
X54400Y217270D01*
G01X52368Y221000D02*
X55600Y217768D01*
G01X46400Y219800D02*
X51870D01*
G01X46898Y221000D02*
X52368D01*
G01X37000Y229200D02*
X46400Y219800D01*
G01X38200Y229698D02*
X46898Y221000D01*
G01X37000Y244300D02*
Y229200D01*
G01X38200Y243802D02*
Y229698D01*
G01X32697Y242529D02*
Y244598D01*
G01X31497Y228705D02*
Y245096D01*
G01X32697Y238629D02*
Y239829D01*
G01X31497Y228705D02*
Y245096D01*
G01X32697Y229203D02*
Y235929D01*
G01X31497Y228705D02*
Y245096D01*
G01X40250Y221650D02*
X32697Y229203D01*
G01X39050Y221152D02*
X31497Y228705D01*
G01X40250Y217728D02*
Y221650D01*
G01X39050Y217728D02*
Y221152D01*
G01X58502Y268500D02*
X56793D01*
G01X59000Y267300D02*
X56807D01*
G01X61202Y271200D02*
X58502Y268500D01*
G01X61700Y270000D02*
X59000Y267300D01*
G01X67774Y271200D02*
X61202D01*
G01X67276Y270000D02*
X61700D01*
G01X60139Y262925D02*
X62700D01*
G01X60637Y261725D02*
X62700D01*
G01X58700Y261486D02*
X60139Y262925D01*
G01X59900Y260988D02*
X60637Y261725D01*
G01X58700Y256302D02*
Y261486D01*
G01X59900Y256800D02*
Y260988D01*
G01X80700Y234302D02*
X58700Y256302D01*
G01X81900Y234800D02*
X59900Y256800D01*
G01X59000Y267300D02*
X56807D01*
G01X58502Y268500D02*
X56793D01*
G01X61700Y270000D02*
X59000Y267300D01*
G01X61202Y271200D02*
X58502Y268500D01*
G01X67276Y270000D02*
X61700D01*
G01X67774Y271200D02*
X61202D01*
G01X60637Y261725D02*
X62700D01*
G01X60139Y262925D02*
X62700D01*
G01X59900Y260988D02*
X60637Y261725D01*
G01X58700Y261486D02*
X60139Y262925D01*
G01X59900Y256800D02*
Y260988D01*
G01X58700Y256302D02*
Y261486D01*
G01X81900Y234800D02*
X59900Y256800D01*
G01X80700Y234302D02*
X58700Y256302D01*
G01X51800Y257402D02*
X38200Y243802D01*
G01X50600Y257900D02*
X37000Y244300D01*
G01X51800Y270100D02*
Y257402D01*
G01X50600Y270598D02*
Y257900D01*
G01X53700Y272000D02*
X51800Y270100D01*
G01X53202Y273200D02*
X50600Y270598D01*
G01X55998Y272000D02*
X53700D01*
G01X55500Y273200D02*
X53202D01*
G01X64400Y280402D02*
X55998Y272000D01*
G01X63200Y280900D02*
X55500Y273200D01*
G01X53599Y275600D02*
X56199Y278200D01*
G01X52207Y275600D02*
X53599D01*
G01X46999Y272090D02*
X51709Y276800D01*
G01X52207Y275600D02*
X53599D01*
G01X48199Y271592D02*
X52207Y275600D01*
G01X46999Y260598D02*
Y272090D01*
G01X48199Y260100D02*
Y271592D01*
G01X31497Y245096D02*
X46999Y260598D01*
G01X46212Y258113D02*
X48199Y260100D01*
G01X43454Y255355D02*
X44302Y256203D01*
G01X40696Y252597D02*
X41545Y253446D01*
G01X37939Y249840D02*
X38787Y250688D01*
G01X32697Y244598D02*
X36029Y247930D01*
G01X50600Y257900D02*
X37000Y244300D01*
G01X51800Y257402D02*
X38200Y243802D01*
G01X50600Y270598D02*
Y257900D01*
G01X51800Y270100D02*
Y257402D01*
G01X53202Y273200D02*
X50600Y270598D01*
G01X53700Y272000D02*
X51800Y270100D01*
G01X55500Y273200D02*
X53202D01*
G01X55998Y272000D02*
X53700D01*
G01X63200Y280900D02*
X55500Y273200D01*
G01X64400Y280402D02*
X55998Y272000D01*
G01X53599Y275600D02*
X56199Y278200D01*
G01X52207Y275600D02*
X53599D01*
G01X46999Y272090D02*
X51709Y276800D01*
G01X48199Y271592D02*
X52207Y275600D01*
G01X46999Y272090D02*
X51709Y276800D01*
G01X48199Y260100D02*
Y271592D01*
G01X46999Y260598D02*
Y272090D01*
G01X46212Y258113D02*
X48199Y260100D01*
G01X31497Y245096D02*
X46999Y260598D01*
G01X43454Y255355D02*
X44302Y256203D01*
G01X31497Y245096D02*
X46999Y260598D01*
G01X40696Y252597D02*
X41545Y253446D01*
G01X31497Y245096D02*
X46999Y260598D01*
G01X37939Y249840D02*
X38787Y250688D01*
G01X31497Y245096D02*
X46999Y260598D01*
G01X32697Y244598D02*
X36029Y247930D01*
G01X31497Y245096D02*
X46999Y260598D01*
G01X63200Y287256D02*
Y280900D01*
G01X61302Y295100D02*
X67900D01*
G01X61800Y293900D02*
X67402D01*
G01X54999Y288797D02*
X61302Y295100D01*
G01X56199Y288299D02*
X61800Y293900D01*
G01X54999Y278698D02*
Y288797D01*
G01X56199Y278200D02*
Y288299D01*
G01X53101Y276800D02*
X54999Y278698D01*
G01X51709Y276800D02*
X53101D01*
G01X63200Y287256D02*
Y280900D01*
G01X61800Y293900D02*
X67402D01*
G01X61302Y295100D02*
X67900D01*
G01X56199Y288299D02*
X61800Y293900D01*
G01X54999Y288797D02*
X61302Y295100D01*
G01X56199Y278200D02*
Y288299D01*
G01X54999Y278698D02*
Y288797D01*
G01X53101Y276800D02*
X54999Y278698D01*
G01X51709Y276800D02*
X53101D01*
G01X85500Y238900D02*
X75727Y248673D01*
G01X84300Y238402D02*
X74527Y248175D01*
G01X85500Y220100D02*
Y238900D01*
G01X84300Y219602D02*
Y238402D01*
G01X90900Y214700D02*
X85500Y220100D01*
G01X89700Y214202D02*
X84300Y219602D01*
G01X90900Y211951D02*
Y214700D01*
G01X89700Y211751D02*
Y214202D01*
G01X80700Y227098D02*
Y234302D01*
G01X81900Y226600D02*
Y234800D01*
G01X75200Y221598D02*
X80700Y227098D01*
G01X76400Y221100D02*
X81900Y226600D01*
G01X75200Y217528D02*
Y221598D01*
G01X76400Y217528D02*
Y221100D01*
G01X84300Y238402D02*
X74527Y248175D01*
G01X85500Y238900D02*
X75727Y248673D01*
G01X84300Y219602D02*
Y238402D01*
G01X85500Y220100D02*
Y238900D01*
G01X89700Y214202D02*
X84300Y219602D01*
G01X90900Y214700D02*
X85500Y220100D01*
G01X89700Y211751D02*
Y214202D01*
G01X90900Y211951D02*
Y214700D01*
G01X81900Y226600D02*
Y234800D01*
G01X80700Y227098D02*
Y234302D01*
G01X76400Y221100D02*
X81900Y226600D01*
G01X75200Y221598D02*
X80700Y227098D01*
G01X76400Y217528D02*
Y221100D01*
G01X75200Y217528D02*
Y221598D01*
G01X75727Y263247D02*
X67774Y271200D01*
G01X74527Y262749D02*
X67276Y270000D01*
G01X75727Y248673D02*
Y263247D01*
G01X74527Y248175D02*
Y262749D01*
G01D02*
X67276Y270000D01*
G01X75727Y263247D02*
X67774Y271200D01*
G01X74527Y248175D02*
Y262749D01*
G01X75727Y248673D02*
Y263247D01*
G01X64400Y287256D02*
Y280402D01*
G01X75325Y290773D02*
Y289231D01*
G01X74125Y290275D02*
Y289231D01*
G01X73298Y292800D02*
X75325Y290773D01*
G01X72800Y291600D02*
X74125Y290275D01*
G01X70200Y292800D02*
X73298D01*
G01X69702Y291600D02*
X72800D01*
G01X67900Y295100D02*
X70200Y292800D01*
G01X67402Y293900D02*
X69702Y291600D01*
G01X64400Y287256D02*
Y280402D01*
G01X74125Y290275D02*
Y289231D01*
G01X75325Y290773D02*
Y289231D01*
G01X72800Y291600D02*
X74125Y290275D01*
G01X73298Y292800D02*
X75325Y290773D01*
G01X69702Y291600D02*
X72800D01*
G01X70200Y292800D02*
X73298D01*
G01X67402Y293900D02*
X69702Y291600D01*
G01X67900Y295100D02*
X70200Y292800D01*
G54D12*
G01X-27072Y-83981D02*
Y-101481D01*
G01X-32094Y-83981D02*
X-22050D01*
G01X-13284Y-101481D02*
Y-83981D01*
G01Y-92439D02*
X-12192Y-90981D01*
X-11100Y-90106D01*
X-9354Y-89815D01*
X-8044Y-90106D01*
X-6515Y-91273D01*
X-5860Y-93023D01*
Y-101481D01*
G01X7928Y-89815D02*
Y-101481D01*
G01Y-85148D02*
X7491Y-84856D01*
Y-84273D01*
X7928Y-83981D01*
X8365Y-84273D01*
Y-84856D01*
X7928Y-85148D01*
G01X22153Y-99440D02*
X23245Y-100606D01*
X24773Y-101481D01*
X26083D01*
X27393Y-100898D01*
X28266Y-100023D01*
X28703Y-98857D01*
X28485Y-97106D01*
X27611Y-96231D01*
X23681Y-94481D01*
X22808Y-92439D01*
X23245Y-90981D01*
X24118Y-90106D01*
X25428Y-89815D01*
X26738Y-90106D01*
X28048Y-90981D01*
G01X57371Y-105856D02*
X58900Y-107023D01*
X60646Y-107314D01*
X62174Y-107023D01*
X63485Y-105565D01*
X64358Y-103523D01*
Y-89815D01*
G01Y-92148D02*
X63485Y-90981D01*
X62174Y-90106D01*
X60646Y-89815D01*
X58900Y-90398D01*
X57808Y-91564D01*
X56934Y-93606D01*
X56498Y-95648D01*
X56716Y-97398D01*
X57590Y-99440D01*
X58900Y-100898D01*
X60646Y-101481D01*
X61956Y-101189D01*
X63485Y-100023D01*
X64358Y-98857D01*
G01X74653Y-93606D02*
X81640D01*
X80985Y-91564D01*
X79893Y-90398D01*
X78365Y-89815D01*
X76836Y-90106D01*
X75526Y-90981D01*
X74653Y-93023D01*
X74216Y-94773D01*
Y-96523D01*
X74653Y-98273D01*
X75745Y-100023D01*
X77055Y-101189D01*
X78583Y-101481D01*
X80111Y-100898D01*
X81640Y-99148D01*
G01X92371Y-101481D02*
Y-89815D01*
G01Y-92148D02*
X93463Y-90981D01*
X94555Y-90106D01*
X96083Y-89815D01*
X97174Y-90106D01*
X98485Y-90981D01*
G01X108998Y-101481D02*
Y-83981D01*
G01Y-92731D02*
X110090Y-90981D01*
X111400Y-90106D01*
X112710Y-89815D01*
X114674Y-90398D01*
X115985Y-91564D01*
X116858Y-93606D01*
Y-95939D01*
X116421Y-98273D01*
X115548Y-100023D01*
X114020Y-101189D01*
X112710Y-101481D01*
X111400Y-101189D01*
X110090Y-100315D01*
X108998Y-98857D01*
G01X127153Y-93606D02*
X134140D01*
X133485Y-91564D01*
X132393Y-90398D01*
X130865Y-89815D01*
X129336Y-90106D01*
X128026Y-90981D01*
X127153Y-93023D01*
X126716Y-94773D01*
Y-96523D01*
X127153Y-98273D01*
X128245Y-100023D01*
X129555Y-101189D01*
X131083Y-101481D01*
X132611Y-100898D01*
X134140Y-99148D01*
G01X144871Y-101481D02*
Y-89815D01*
G01Y-92148D02*
X145963Y-90981D01*
X147055Y-90106D01*
X148583Y-89815D01*
X149674Y-90106D01*
X150985Y-90981D01*
G01X182928Y-89815D02*
Y-101481D01*
G01Y-85148D02*
X182491Y-84856D01*
Y-84273D01*
X182928Y-83981D01*
X183365Y-84273D01*
Y-84856D01*
X182928Y-85148D01*
G01X197153Y-99440D02*
X198245Y-100606D01*
X199773Y-101481D01*
X201083D01*
X202393Y-100898D01*
X203266Y-100023D01*
X203703Y-98857D01*
X203485Y-97106D01*
X202611Y-96231D01*
X198681Y-94481D01*
X197808Y-92439D01*
X198245Y-90981D01*
X199118Y-90106D01*
X200428Y-89815D01*
X201738Y-90106D01*
X203048Y-90981D01*
G01X231934Y-105856D02*
X233463Y-107023D01*
X234773Y-107314D01*
X236520Y-106731D01*
X237830Y-105273D01*
X238485Y-102647D01*
Y-89815D01*
G01Y-85148D02*
X238048Y-84856D01*
Y-84273D01*
X238485Y-83981D01*
X238921Y-84273D01*
Y-84856D01*
X238485Y-85148D01*
G01X249216Y-89815D02*
Y-97981D01*
X250090Y-100023D01*
X251400Y-101189D01*
X252928Y-101481D01*
X254456Y-101189D01*
X255766Y-100023D01*
X256640Y-97981D01*
G01Y-101481D02*
Y-89815D01*
G01X267153Y-99440D02*
X268245Y-100606D01*
X269773Y-101481D01*
X271083D01*
X272393Y-100898D01*
X273266Y-100023D01*
X273703Y-98857D01*
X273485Y-97106D01*
X272611Y-96231D01*
X268681Y-94481D01*
X267808Y-92439D01*
X268245Y-90981D01*
X269118Y-90106D01*
X270428Y-89815D01*
X271738Y-90106D01*
X273048Y-90981D01*
G01X287928Y-83981D02*
Y-101481D01*
G01X284871Y-89815D02*
X290985D01*
G01X321618Y-101481D02*
Y-86606D01*
X322055Y-85148D01*
X322928Y-84273D01*
X324238Y-83981D01*
X325548Y-84564D01*
X326203Y-86023D01*
G01X323583Y-90981D02*
X319216D01*
G01X340428Y-101481D02*
X339118Y-101189D01*
X337808Y-100023D01*
X336934Y-97981D01*
X336498Y-95648D01*
X336934Y-93314D01*
X337808Y-91273D01*
X339118Y-90106D01*
X340428Y-89815D01*
X341738Y-90106D01*
X343048Y-91273D01*
X343921Y-93314D01*
X344140Y-95648D01*
X343921Y-97981D01*
X343048Y-100023D01*
X341738Y-101189D01*
X340428Y-101481D01*
G01X354871D02*
Y-89815D01*
G01Y-92148D02*
X355963Y-90981D01*
X357055Y-90106D01*
X358583Y-89815D01*
X359674Y-90106D01*
X360985Y-90981D01*
G01X388343Y-106731D02*
X389653Y-107314D01*
X391400Y-106731D01*
X392491Y-105565D01*
X393365Y-104106D01*
X394674Y-99440D01*
X397513Y-89815D01*
G01X390526D02*
X394674Y-99440D01*
G01X410428Y-101481D02*
X409118Y-101189D01*
X407808Y-100023D01*
X406934Y-97981D01*
X406498Y-95648D01*
X406934Y-93314D01*
X407808Y-91273D01*
X409118Y-90106D01*
X410428Y-89815D01*
X411738Y-90106D01*
X413048Y-91273D01*
X413921Y-93314D01*
X414140Y-95648D01*
X413921Y-97981D01*
X413048Y-100023D01*
X411738Y-101189D01*
X410428Y-101481D01*
G01X424216Y-89815D02*
Y-97981D01*
X425090Y-100023D01*
X426400Y-101189D01*
X427928Y-101481D01*
X429456Y-101189D01*
X430766Y-100023D01*
X431640Y-97981D01*
G01Y-101481D02*
Y-89815D01*
G01X442371Y-101481D02*
Y-89815D01*
G01Y-92148D02*
X443463Y-90981D01*
X444555Y-90106D01*
X446083Y-89815D01*
X447174Y-90106D01*
X448485Y-90981D01*
G01X477371Y-101481D02*
Y-89815D01*
G01Y-92148D02*
X478463Y-90981D01*
X479555Y-90106D01*
X481083Y-89815D01*
X482174Y-90106D01*
X483485Y-90981D01*
G01X494653Y-93606D02*
X501640D01*
X500985Y-91564D01*
X499893Y-90398D01*
X498365Y-89815D01*
X496836Y-90106D01*
X495526Y-90981D01*
X494653Y-93023D01*
X494216Y-94773D01*
Y-96523D01*
X494653Y-98273D01*
X495745Y-100023D01*
X497055Y-101189D01*
X498583Y-101481D01*
X500111Y-100898D01*
X501640Y-99148D01*
G01X514118Y-101481D02*
Y-86606D01*
X514555Y-85148D01*
X515428Y-84273D01*
X516738Y-83981D01*
X518048Y-84564D01*
X518703Y-86023D01*
G01X516083Y-90981D02*
X511716D01*
G01X529653Y-93606D02*
X536640D01*
X535985Y-91564D01*
X534893Y-90398D01*
X533365Y-89815D01*
X531836Y-90106D01*
X530526Y-90981D01*
X529653Y-93023D01*
X529216Y-94773D01*
Y-96523D01*
X529653Y-98273D01*
X530745Y-100023D01*
X532055Y-101189D01*
X533583Y-101481D01*
X535111Y-100898D01*
X536640Y-99148D01*
G01X547371Y-101481D02*
Y-89815D01*
G01Y-92148D02*
X548463Y-90981D01*
X549555Y-90106D01*
X551083Y-89815D01*
X552174Y-90106D01*
X553485Y-90981D01*
G01X564653Y-93606D02*
X571640D01*
X570985Y-91564D01*
X569893Y-90398D01*
X568365Y-89815D01*
X566836Y-90106D01*
X565526Y-90981D01*
X564653Y-93023D01*
X564216Y-94773D01*
Y-96523D01*
X564653Y-98273D01*
X565745Y-100023D01*
X567055Y-101189D01*
X568583Y-101481D01*
X570111Y-100898D01*
X571640Y-99148D01*
G01X581716Y-101481D02*
Y-89815D01*
G01Y-92731D02*
X582590Y-91273D01*
X583900Y-90106D01*
X585646Y-89815D01*
X587174Y-90106D01*
X588485Y-91273D01*
X589140Y-93314D01*
Y-101481D01*
G01X606421Y-91273D02*
X604893Y-90106D01*
X603583Y-89815D01*
X601836Y-90398D01*
X600526Y-91564D01*
X599653Y-93606D01*
X599434Y-95648D01*
X599653Y-97690D01*
X600526Y-99440D01*
X601836Y-100898D01*
X603583Y-101481D01*
X605111Y-100898D01*
X606421Y-99731D01*
G01X617153Y-93606D02*
X624140D01*
X623485Y-91564D01*
X622393Y-90398D01*
X620865Y-89815D01*
X619336Y-90106D01*
X618026Y-90981D01*
X617153Y-93023D01*
X616716Y-94773D01*
Y-96523D01*
X617153Y-98273D01*
X618245Y-100023D01*
X619555Y-101189D01*
X621083Y-101481D01*
X622611Y-100898D01*
X624140Y-99148D01*
G01X655428Y-83981D02*
Y-101481D01*
G01X652371Y-89815D02*
X658485D01*
G01X672928Y-101481D02*
X671618Y-101189D01*
X670308Y-100023D01*
X669434Y-97981D01*
X668998Y-95648D01*
X669434Y-93314D01*
X670308Y-91273D01*
X671618Y-90106D01*
X672928Y-89815D01*
X674238Y-90106D01*
X675548Y-91273D01*
X676421Y-93314D01*
X676640Y-95648D01*
X676421Y-97981D01*
X675548Y-100023D01*
X674238Y-101189D01*
X672928Y-101481D01*
G01X706618D02*
Y-86606D01*
X707055Y-85148D01*
X707928Y-84273D01*
X709238Y-83981D01*
X710548Y-84564D01*
X711203Y-86023D01*
G01X708583Y-90981D02*
X704216D01*
G01X725428Y-89815D02*
Y-101481D01*
G01Y-85148D02*
X724991Y-84856D01*
Y-84273D01*
X725428Y-83981D01*
X725865Y-84273D01*
Y-84856D01*
X725428Y-85148D01*
G01X739216Y-101481D02*
Y-89815D01*
G01Y-92731D02*
X740090Y-91273D01*
X741400Y-90106D01*
X743146Y-89815D01*
X744674Y-90106D01*
X745985Y-91273D01*
X746640Y-93314D01*
Y-101481D01*
G01X764358Y-83981D02*
Y-101481D01*
G01Y-98857D02*
X763485Y-100315D01*
X762174Y-101189D01*
X760646Y-101481D01*
X758900Y-100898D01*
X757590Y-99440D01*
X756716Y-97690D01*
X756498Y-95648D01*
X756716Y-93606D01*
X757590Y-91856D01*
X758900Y-90398D01*
X760646Y-89815D01*
X762174Y-90106D01*
X763266Y-90690D01*
X764358Y-91856D01*
G01X795428Y-83981D02*
Y-101481D01*
G01X792371Y-89815D02*
X798485D01*
G01X809216Y-101481D02*
Y-83981D01*
G01Y-92439D02*
X810308Y-90981D01*
X811400Y-90106D01*
X813146Y-89815D01*
X814456Y-90106D01*
X815985Y-91273D01*
X816640Y-93023D01*
Y-101481D01*
G01X827153Y-93606D02*
X834140D01*
X833485Y-91564D01*
X832393Y-90398D01*
X830865Y-89815D01*
X829336Y-90106D01*
X828026Y-90981D01*
X827153Y-93023D01*
X826716Y-94773D01*
Y-96523D01*
X827153Y-98273D01*
X828245Y-100023D01*
X829555Y-101189D01*
X831083Y-101481D01*
X832611Y-100898D01*
X834140Y-99148D01*
G01X860625Y-101481D02*
Y-83981D01*
X864991D01*
X866738Y-84856D01*
X868048Y-86023D01*
X869140Y-87772D01*
X870013Y-89815D01*
X870231Y-92731D01*
X870013Y-95648D01*
X869140Y-97690D01*
X868048Y-99440D01*
X866738Y-100606D01*
X864991Y-101481D01*
X860625D01*
G01X878561D02*
Y-83981D01*
X883801D01*
X885548Y-84856D01*
X886858Y-86898D01*
X887295Y-89231D01*
X886858Y-91564D01*
X885766Y-93314D01*
X883801Y-94190D01*
X878561D01*
G01X917928Y-89815D02*
Y-101481D01*
G01Y-85148D02*
X917491Y-84856D01*
Y-84273D01*
X917928Y-83981D01*
X918365Y-84273D01*
Y-84856D01*
X917928Y-85148D01*
G01X928878Y-101481D02*
Y-89815D01*
G01Y-93023D02*
X929533Y-91564D01*
X930625Y-90398D01*
X932153Y-89815D01*
X933681Y-90398D01*
X934773Y-91564D01*
X935428Y-93023D01*
Y-101481D01*
G01Y-93023D02*
X936083Y-91564D01*
X937174Y-90398D01*
X938703Y-89815D01*
X940231Y-90398D01*
X941323Y-91564D01*
X941978Y-93314D01*
Y-101481D01*
G01X948998Y-107314D02*
Y-89815D01*
G01Y-92439D02*
X950090Y-90981D01*
X951181Y-90106D01*
X952928Y-89815D01*
X954456Y-90106D01*
X955985Y-91564D01*
X956640Y-93606D01*
X956858Y-95648D01*
X956640Y-97690D01*
X955985Y-99731D01*
X954674Y-100898D01*
X952928Y-101481D01*
X951400Y-101189D01*
X949871Y-100315D01*
X948998Y-99148D01*
G01X967153Y-93606D02*
X974140D01*
X973485Y-91564D01*
X972393Y-90398D01*
X970865Y-89815D01*
X969336Y-90106D01*
X968026Y-90981D01*
X967153Y-93023D01*
X966716Y-94773D01*
Y-96523D01*
X967153Y-98273D01*
X968245Y-100023D01*
X969555Y-101189D01*
X971083Y-101481D01*
X972611Y-100898D01*
X974140Y-99148D01*
G01X991858Y-83981D02*
Y-101481D01*
G01Y-98857D02*
X990985Y-100315D01*
X989674Y-101189D01*
X988146Y-101481D01*
X986400Y-100898D01*
X985090Y-99440D01*
X984216Y-97690D01*
X983998Y-95648D01*
X984216Y-93606D01*
X985090Y-91856D01*
X986400Y-90398D01*
X988146Y-89815D01*
X989674Y-90106D01*
X990766Y-90690D01*
X991858Y-91856D01*
G01X1009358Y-101481D02*
Y-89815D01*
G01Y-91856D02*
X1008485Y-90690D01*
X1007174Y-90106D01*
X1005646Y-89815D01*
X1004118Y-90398D01*
X1002808Y-91564D01*
X1001934Y-93314D01*
X1001498Y-95648D01*
X1001934Y-97981D01*
X1002808Y-99731D01*
X1004118Y-100898D01*
X1005646Y-101481D01*
X1007174Y-101189D01*
X1008485Y-100315D01*
X1009358Y-99148D01*
G01X1019216Y-101481D02*
Y-89815D01*
G01Y-92731D02*
X1020090Y-91273D01*
X1021400Y-90106D01*
X1023146Y-89815D01*
X1024674Y-90106D01*
X1025985Y-91273D01*
X1026640Y-93314D01*
Y-101481D01*
G01X1043921Y-91273D02*
X1042393Y-90106D01*
X1041083Y-89815D01*
X1039336Y-90398D01*
X1038026Y-91564D01*
X1037153Y-93606D01*
X1036934Y-95648D01*
X1037153Y-97690D01*
X1038026Y-99440D01*
X1039336Y-100898D01*
X1041083Y-101481D01*
X1042611Y-100898D01*
X1043921Y-99731D01*
G01X1054653Y-93606D02*
X1061640D01*
X1060985Y-91564D01*
X1059893Y-90398D01*
X1058365Y-89815D01*
X1056836Y-90106D01*
X1055526Y-90981D01*
X1054653Y-93023D01*
X1054216Y-94773D01*
Y-96523D01*
X1054653Y-98273D01*
X1055745Y-100023D01*
X1057055Y-101189D01*
X1058583Y-101481D01*
X1060111Y-100898D01*
X1061640Y-99148D01*
G01X1092928Y-83981D02*
Y-101481D01*
G01X1089871Y-89815D02*
X1095985D01*
G01X1107371Y-101481D02*
Y-89815D01*
G01Y-92148D02*
X1108463Y-90981D01*
X1109555Y-90106D01*
X1111083Y-89815D01*
X1112174Y-90106D01*
X1113485Y-90981D01*
G01X1131858Y-101481D02*
Y-89815D01*
G01Y-91856D02*
X1130985Y-90690D01*
X1129674Y-90106D01*
X1128146Y-89815D01*
X1126618Y-90398D01*
X1125308Y-91564D01*
X1124434Y-93314D01*
X1123998Y-95648D01*
X1124434Y-97981D01*
X1125308Y-99731D01*
X1126618Y-100898D01*
X1128146Y-101481D01*
X1129674Y-101189D01*
X1130985Y-100315D01*
X1131858Y-99148D01*
G01X1148921Y-91273D02*
X1147393Y-90106D01*
X1146083Y-89815D01*
X1144336Y-90398D01*
X1143026Y-91564D01*
X1142153Y-93606D01*
X1141934Y-95648D01*
X1142153Y-97690D01*
X1143026Y-99440D01*
X1144336Y-100898D01*
X1146083Y-101481D01*
X1147611Y-100898D01*
X1148921Y-99731D01*
G01X1159653Y-93606D02*
X1166640D01*
X1165985Y-91564D01*
X1164893Y-90398D01*
X1163365Y-89815D01*
X1161836Y-90106D01*
X1160526Y-90981D01*
X1159653Y-93023D01*
X1159216Y-94773D01*
Y-96523D01*
X1159653Y-98273D01*
X1160745Y-100023D01*
X1162055Y-101189D01*
X1163583Y-101481D01*
X1165111Y-100898D01*
X1166640Y-99148D01*
G01X1177153Y-99440D02*
X1178245Y-100606D01*
X1179773Y-101481D01*
X1181083D01*
X1182393Y-100898D01*
X1183266Y-100023D01*
X1183703Y-98857D01*
X1183485Y-97106D01*
X1182611Y-96231D01*
X1178681Y-94481D01*
X1177808Y-92439D01*
X1178245Y-90981D01*
X1179118Y-90106D01*
X1180428Y-89815D01*
X1181738Y-90106D01*
X1183048Y-90981D01*
G01X1215428Y-89815D02*
Y-101481D01*
G01Y-85148D02*
X1214991Y-84856D01*
Y-84273D01*
X1215428Y-83981D01*
X1215865Y-84273D01*
Y-84856D01*
X1215428Y-85148D01*
G01X1229216Y-101481D02*
Y-89815D01*
G01Y-92731D02*
X1230090Y-91273D01*
X1231400Y-90106D01*
X1233146Y-89815D01*
X1234674Y-90106D01*
X1235985Y-91273D01*
X1236640Y-93314D01*
Y-101481D01*
G01X1267928D02*
Y-83981D01*
G01X1289358Y-101481D02*
Y-89815D01*
G01Y-91856D02*
X1288485Y-90690D01*
X1287174Y-90106D01*
X1285646Y-89815D01*
X1284118Y-90398D01*
X1282808Y-91564D01*
X1281934Y-93314D01*
X1281498Y-95648D01*
X1281934Y-97981D01*
X1282808Y-99731D01*
X1284118Y-100898D01*
X1285646Y-101481D01*
X1287174Y-101189D01*
X1288485Y-100315D01*
X1289358Y-99148D01*
G01X1298343Y-106731D02*
X1299653Y-107314D01*
X1301400Y-106731D01*
X1302491Y-105565D01*
X1303365Y-104106D01*
X1304674Y-99440D01*
X1307513Y-89815D01*
G01X1300526D02*
X1304674Y-99440D01*
G01X1317153Y-93606D02*
X1324140D01*
X1323485Y-91564D01*
X1322393Y-90398D01*
X1320865Y-89815D01*
X1319336Y-90106D01*
X1318026Y-90981D01*
X1317153Y-93023D01*
X1316716Y-94773D01*
Y-96523D01*
X1317153Y-98273D01*
X1318245Y-100023D01*
X1319555Y-101189D01*
X1321083Y-101481D01*
X1322611Y-100898D01*
X1324140Y-99148D01*
G01X1334871Y-101481D02*
Y-89815D01*
G01Y-92148D02*
X1335963Y-90981D01*
X1337055Y-90106D01*
X1338583Y-89815D01*
X1339674Y-90106D01*
X1340985Y-90981D01*
G01X1368561Y-83981D02*
Y-101481D01*
X1377295D01*
G01X1386280Y-94190D02*
X1387808Y-92148D01*
X1389118Y-90981D01*
X1390865Y-90398D01*
X1392393Y-90981D01*
X1393485Y-92148D01*
X1394358Y-93898D01*
X1394576Y-95939D01*
X1394358Y-97690D01*
X1393485Y-99440D01*
X1392174Y-100898D01*
X1390646Y-101481D01*
X1388900Y-100898D01*
X1387371Y-99148D01*
X1386498Y-96523D01*
X1386280Y-93606D01*
X1386716Y-89815D01*
X1387371Y-87772D01*
X1388463Y-85731D01*
X1389991Y-84273D01*
X1391520Y-83981D01*
X1393048Y-84564D01*
X1394140Y-86023D01*
G01X1407928Y-102064D02*
X1407491Y-101773D01*
Y-101189D01*
X1407928Y-100898D01*
X1408365Y-101189D01*
Y-101773D01*
X1407928Y-102064D01*
G01X1481717Y873038D02*
Y890538D01*
X1486083D01*
X1487830Y889663D01*
X1489140Y888496D01*
X1490232Y886747D01*
X1491105Y884704D01*
X1491323Y881788D01*
X1491105Y878871D01*
X1490232Y876829D01*
X1489140Y875079D01*
X1487830Y873913D01*
X1486083Y873038D01*
X1481717D01*
G01X1499653D02*
Y890538D01*
X1504893D01*
X1506640Y889663D01*
X1507950Y887621D01*
X1508387Y885288D01*
X1507950Y882955D01*
X1506858Y881205D01*
X1504893Y880329D01*
X1499653D01*
G01X1536400Y890538D02*
X1541640D01*
G01X1539020D02*
Y873038D01*
G01X1536400D02*
X1541640D01*
G01X1550843D02*
Y890538D01*
X1556520Y875955D01*
X1562197Y890538D01*
Y873038D01*
G01X1569653D02*
Y890538D01*
X1574893D01*
X1576640Y889663D01*
X1577950Y887621D01*
X1578387Y885288D01*
X1577950Y882955D01*
X1576858Y881205D01*
X1574893Y880329D01*
X1569653D01*
G01X1595887Y873038D02*
X1587153D01*
Y890538D01*
X1595887D01*
G01X1592393Y882080D02*
X1587153D01*
G01X1604217Y873038D02*
Y890538D01*
X1608583D01*
X1610330Y889663D01*
X1611640Y888496D01*
X1612732Y886747D01*
X1613605Y884704D01*
X1613823Y881788D01*
X1613605Y878871D01*
X1612732Y876829D01*
X1611640Y875079D01*
X1610330Y873913D01*
X1608583Y873038D01*
X1604217D01*
G01X1621061D02*
X1626520Y890538D01*
X1631979Y873038D01*
G01X1630013Y879163D02*
X1623026D01*
G01X1638998Y873038D02*
Y890538D01*
X1649042Y873038D01*
Y890538D01*
G01X1666323Y889079D02*
X1665013Y889955D01*
X1663485Y890538D01*
X1661738D01*
X1659773Y889663D01*
X1658245Y888205D01*
X1657153Y886454D01*
X1656280Y883538D01*
X1656061Y880913D01*
X1656498Y878288D01*
X1657153Y876538D01*
X1658463Y874788D01*
X1659992Y873621D01*
X1661520Y873038D01*
X1663048D01*
X1664577Y873621D01*
X1665887Y874496D01*
X1666979Y875662D01*
G01X1683387Y873038D02*
X1674653D01*
Y890538D01*
X1683387D01*
G01X1679893Y882080D02*
X1674653D01*
G01X1714020Y890538D02*
Y873038D01*
G01X1708998Y890538D02*
X1719042D01*
G01X1726061Y873038D02*
X1731520Y890538D01*
X1736979Y873038D01*
G01X1735013Y879163D02*
X1728026D01*
G01X1750766Y882371D02*
X1751640Y883246D01*
X1752295Y884704D01*
X1752732Y886747D01*
X1752295Y888496D01*
X1751422Y889663D01*
X1749893Y890538D01*
X1743998D01*
Y873038D01*
X1751203D01*
X1752732Y874204D01*
X1753605Y875955D01*
X1754042Y877996D01*
X1753605Y880038D01*
X1752295Y881788D01*
X1750766Y882371D01*
X1743998D01*
G01X1762153Y890538D02*
Y873038D01*
X1770887D01*
G01X1788387D02*
X1779653D01*
Y890538D01*
X1788387D01*
G01X1784893Y882080D02*
X1779653D01*
G01X1801520Y872455D02*
X1801083Y872746D01*
Y873330D01*
X1801520Y873621D01*
X1801957Y873330D01*
Y872746D01*
X1801520Y872455D01*
G01Y880329D02*
X1801083Y880621D01*
Y881205D01*
X1801520Y881496D01*
X1801957Y881205D01*
Y880621D01*
X1801520Y880329D01*
G01X1832153Y890538D02*
Y873038D01*
X1840887D01*
G01X1849872Y880329D02*
X1851400Y882371D01*
X1852710Y883538D01*
X1854457Y884121D01*
X1855985Y883538D01*
X1857077Y882371D01*
X1857950Y880621D01*
X1858168Y878580D01*
X1857950Y876829D01*
X1857077Y875079D01*
X1855766Y873621D01*
X1854238Y873038D01*
X1852492Y873621D01*
X1850963Y875371D01*
X1850090Y877996D01*
X1849872Y880913D01*
X1850308Y884704D01*
X1850963Y886747D01*
X1852055Y888788D01*
X1853583Y890246D01*
X1855112Y890538D01*
X1856640Y889955D01*
X1857732Y888496D01*
G01X1503600Y855888D02*
X1508840D01*
G01X1506220D02*
Y838388D01*
G01X1503600D02*
X1508840D01*
G01X1518043D02*
Y855888D01*
X1523720Y841305D01*
X1529397Y855888D01*
Y838388D01*
G01X1536853D02*
Y855888D01*
X1542093D01*
X1543840Y855013D01*
X1545150Y852971D01*
X1545587Y850638D01*
X1545150Y848305D01*
X1544058Y846555D01*
X1542093Y845679D01*
X1536853D01*
G01X1557628Y832555D02*
X1555445Y835471D01*
X1554353Y838388D01*
Y850054D01*
X1555445Y852971D01*
X1557628Y855888D01*
G01X1576220Y838388D02*
X1574473Y838680D01*
X1572945Y839846D01*
X1571635Y841596D01*
X1570761Y843638D01*
X1570325Y845971D01*
Y848305D01*
X1570761Y850638D01*
X1571635Y852680D01*
X1572945Y854429D01*
X1574473Y855596D01*
X1576220Y855888D01*
X1577966Y855596D01*
X1579495Y854429D01*
X1580805Y852680D01*
X1581679Y850638D01*
X1582115Y848305D01*
Y845971D01*
X1581679Y843638D01*
X1580805Y841596D01*
X1579495Y839846D01*
X1577966Y838680D01*
X1576220Y838388D01*
G01X1590008D02*
Y855888D01*
G01Y847430D02*
X1591100Y848888D01*
X1592192Y849763D01*
X1593938Y850054D01*
X1595248Y849763D01*
X1596777Y848596D01*
X1597432Y846846D01*
Y838388D01*
G01X1604670D02*
Y850054D01*
G01Y846846D02*
X1605325Y848305D01*
X1606417Y849471D01*
X1607945Y850054D01*
X1609473Y849471D01*
X1610565Y848305D01*
X1611220Y846846D01*
Y838388D01*
G01Y846846D02*
X1611875Y848305D01*
X1612966Y849471D01*
X1614495Y850054D01*
X1616023Y849471D01*
X1617115Y848305D01*
X1617770Y846555D01*
Y838388D01*
G01X1629812Y832555D02*
X1631995Y835471D01*
X1633087Y838388D01*
Y850054D01*
X1631995Y852971D01*
X1629812Y855888D01*
G01X1532470Y769088D02*
Y786588D01*
X1529850Y783088D01*
G01Y769088D02*
X1535090D01*
G01X1549970Y786588D02*
X1548223Y786005D01*
X1546913Y784546D01*
X1546040Y782797D01*
X1545385Y780463D01*
X1545167Y777838D01*
X1545385Y775213D01*
X1546040Y772879D01*
X1546913Y771129D01*
X1548223Y769671D01*
X1549970Y769088D01*
X1551716Y769671D01*
X1553027Y771129D01*
X1553900Y772879D01*
X1554555Y775213D01*
X1554773Y777838D01*
X1554555Y780463D01*
X1553900Y782797D01*
X1553027Y784546D01*
X1551716Y786005D01*
X1549970Y786588D01*
G01X1567470D02*
X1565723Y786005D01*
X1564413Y784546D01*
X1563540Y782797D01*
X1562885Y780463D01*
X1562667Y777838D01*
X1562885Y775213D01*
X1563540Y772879D01*
X1564413Y771129D01*
X1565723Y769671D01*
X1567470Y769088D01*
X1569216Y769671D01*
X1570527Y771129D01*
X1571400Y772879D01*
X1572055Y775213D01*
X1572273Y777838D01*
X1572055Y780463D01*
X1571400Y782797D01*
X1570527Y784546D01*
X1569216Y786005D01*
X1567470Y786588D01*
G01X1584970Y768505D02*
X1584533Y768796D01*
Y769380D01*
X1584970Y769671D01*
X1585407Y769380D01*
Y768796D01*
X1584970Y768505D01*
G01X1602470Y786588D02*
X1600723Y786005D01*
X1599413Y784546D01*
X1598540Y782797D01*
X1597885Y780463D01*
X1597667Y777838D01*
X1597885Y775213D01*
X1598540Y772879D01*
X1599413Y771129D01*
X1600723Y769671D01*
X1602470Y769088D01*
X1604216Y769671D01*
X1605527Y771129D01*
X1606400Y772879D01*
X1607055Y775213D01*
X1607273Y777838D01*
X1607055Y780463D01*
X1606400Y782797D01*
X1605527Y784546D01*
X1604216Y786005D01*
X1602470Y786588D01*
G01X1541220Y803738D02*
X1542748Y804030D01*
X1544495Y804904D01*
X1545587Y806362D01*
X1546023Y808405D01*
X1545587Y810446D01*
X1544277Y812196D01*
X1542312Y813071D01*
X1540128D01*
X1538818Y813655D01*
X1537726Y815113D01*
X1537290Y817154D01*
X1537945Y819196D01*
X1539473Y820655D01*
X1541220Y821238D01*
X1542966Y820655D01*
X1544495Y819196D01*
X1545150Y817154D01*
X1544713Y815113D01*
X1543622Y813655D01*
X1542312Y813071D01*
X1540128D01*
X1538163Y812196D01*
X1536853Y810446D01*
X1536417Y808405D01*
X1536853Y806362D01*
X1537945Y804904D01*
X1539692Y804030D01*
X1541220Y803738D01*
G01X1553917Y806362D02*
X1555226Y804904D01*
X1556755Y804030D01*
X1558720Y803738D01*
X1560685Y804321D01*
X1562213Y805488D01*
X1563305Y807529D01*
X1563523Y809863D01*
X1563087Y812196D01*
X1561995Y813655D01*
X1560466Y814821D01*
X1558938Y815113D01*
X1557410Y814821D01*
X1555445Y813655D01*
X1556100Y821238D01*
X1561995D01*
G01X1576220Y803155D02*
X1575783Y803446D01*
Y804030D01*
X1576220Y804321D01*
X1576657Y804030D01*
Y803446D01*
X1576220Y803155D01*
G01X1593720Y821238D02*
X1591973Y820655D01*
X1590663Y819196D01*
X1589790Y817447D01*
X1589135Y815113D01*
X1588917Y812488D01*
X1589135Y809863D01*
X1589790Y807529D01*
X1590663Y805779D01*
X1591973Y804321D01*
X1593720Y803738D01*
X1595466Y804321D01*
X1596777Y805779D01*
X1597650Y807529D01*
X1598305Y809863D01*
X1598523Y812488D01*
X1598305Y815113D01*
X1597650Y817447D01*
X1596777Y819196D01*
X1595466Y820655D01*
X1593720Y821238D01*
G01X1709670Y855888D02*
X1712726Y838388D01*
X1716220Y855888D01*
X1719713Y838388D01*
X1722770Y855888D01*
G01X1731100D02*
X1736340D01*
G01X1733720D02*
Y838388D01*
G01X1731100D02*
X1736340D01*
G01X1746417D02*
Y855888D01*
X1750783D01*
X1752530Y855013D01*
X1753840Y853846D01*
X1754932Y852097D01*
X1755805Y850054D01*
X1756023Y847138D01*
X1755805Y844221D01*
X1754932Y842179D01*
X1753840Y840429D01*
X1752530Y839263D01*
X1750783Y838388D01*
X1746417D01*
G01X1768720Y855888D02*
Y838388D01*
G01X1763698Y855888D02*
X1773742D01*
G01X1781635Y838388D02*
Y855888D01*
G01X1790805D02*
Y838388D01*
G01Y847138D02*
X1781635D01*
G01X1802628Y832555D02*
X1800445Y835471D01*
X1799353Y838388D01*
Y850054D01*
X1800445Y852971D01*
X1802628Y855888D01*
G01X1814670Y838388D02*
Y850054D01*
G01Y846846D02*
X1815325Y848305D01*
X1816417Y849471D01*
X1817945Y850054D01*
X1819473Y849471D01*
X1820565Y848305D01*
X1821220Y846846D01*
Y838388D01*
G01Y846846D02*
X1821875Y848305D01*
X1822966Y849471D01*
X1824495Y850054D01*
X1826023Y849471D01*
X1827115Y848305D01*
X1827770Y846555D01*
Y838388D01*
G01X1838720Y850054D02*
Y838388D01*
G01Y854721D02*
X1838283Y855013D01*
Y855596D01*
X1838720Y855888D01*
X1839157Y855596D01*
Y855013D01*
X1838720Y854721D01*
G01X1856220Y838388D02*
Y855888D01*
G01X1870445Y840429D02*
X1871537Y839263D01*
X1873065Y838388D01*
X1874375D01*
X1875685Y838971D01*
X1876558Y839846D01*
X1876995Y841012D01*
X1876777Y842763D01*
X1875903Y843638D01*
X1871973Y845388D01*
X1871100Y847430D01*
X1871537Y848888D01*
X1872410Y849763D01*
X1873720Y850054D01*
X1875030Y849763D01*
X1876340Y848888D01*
G01X1892312Y832555D02*
X1894495Y835471D01*
X1895587Y838388D01*
Y850054D01*
X1894495Y852971D01*
X1892312Y855888D01*
G01X1753840Y769088D02*
Y786588D01*
X1745761Y774046D01*
X1756679D01*
G01X1768720Y768505D02*
X1768283Y768796D01*
Y769380D01*
X1768720Y769671D01*
X1769157Y769380D01*
Y768796D01*
X1768720Y768505D01*
G01X1786220Y786588D02*
X1784473Y786005D01*
X1783163Y784546D01*
X1782290Y782797D01*
X1781635Y780463D01*
X1781417Y777838D01*
X1781635Y775213D01*
X1782290Y772879D01*
X1783163Y771129D01*
X1784473Y769671D01*
X1786220Y769088D01*
X1787966Y769671D01*
X1789277Y771129D01*
X1790150Y772879D01*
X1790805Y775213D01*
X1791023Y777838D01*
X1790805Y780463D01*
X1790150Y782797D01*
X1789277Y784546D01*
X1787966Y786005D01*
X1786220Y786588D01*
G01X1799790Y768505D02*
X1807650Y786588D01*
G01X1821220Y769088D02*
X1822748Y769380D01*
X1824495Y770254D01*
X1825587Y771712D01*
X1826023Y773755D01*
X1825587Y775796D01*
X1824277Y777546D01*
X1822312Y778421D01*
X1820128D01*
X1818818Y779005D01*
X1817726Y780463D01*
X1817290Y782504D01*
X1817945Y784546D01*
X1819473Y786005D01*
X1821220Y786588D01*
X1822966Y786005D01*
X1824495Y784546D01*
X1825150Y782504D01*
X1824713Y780463D01*
X1823622Y779005D01*
X1822312Y778421D01*
X1820128D01*
X1818163Y777546D01*
X1816853Y775796D01*
X1816417Y773755D01*
X1816853Y771712D01*
X1817945Y770254D01*
X1819692Y769380D01*
X1821220Y769088D01*
G01X1838720Y768505D02*
X1838283Y768796D01*
Y769380D01*
X1838720Y769671D01*
X1839157Y769380D01*
Y768796D01*
X1838720Y768505D01*
G01X1856220Y786588D02*
X1854473Y786005D01*
X1853163Y784546D01*
X1852290Y782797D01*
X1851635Y780463D01*
X1851417Y777838D01*
X1851635Y775213D01*
X1852290Y772879D01*
X1853163Y771129D01*
X1854473Y769671D01*
X1856220Y769088D01*
X1857966Y769671D01*
X1859277Y771129D01*
X1860150Y772879D01*
X1860805Y775213D01*
X1861023Y777838D01*
X1860805Y780463D01*
X1860150Y782797D01*
X1859277Y784546D01*
X1857966Y786005D01*
X1856220Y786588D01*
G01X1746417Y806362D02*
X1747726Y804904D01*
X1749255Y804030D01*
X1751220Y803738D01*
X1753185Y804321D01*
X1754713Y805488D01*
X1755805Y807529D01*
X1756023Y809863D01*
X1755587Y812196D01*
X1754495Y813655D01*
X1752966Y814821D01*
X1751438Y815113D01*
X1749910Y814821D01*
X1747945Y813655D01*
X1748600Y821238D01*
X1754495D01*
G01X1768720Y803155D02*
X1768283Y803446D01*
Y804030D01*
X1768720Y804321D01*
X1769157Y804030D01*
Y803446D01*
X1768720Y803155D01*
G01X1781417Y806362D02*
X1782726Y804904D01*
X1784255Y804030D01*
X1786220Y803738D01*
X1788185Y804321D01*
X1789713Y805488D01*
X1790805Y807529D01*
X1791023Y809863D01*
X1790587Y812196D01*
X1789495Y813655D01*
X1787966Y814821D01*
X1786438Y815113D01*
X1784910Y814821D01*
X1782945Y813655D01*
X1783600Y821238D01*
X1789495D01*
G01X1799790Y803155D02*
X1807650Y821238D01*
G01X1820783Y803738D02*
X1821220Y807529D01*
X1821875Y810738D01*
X1822748Y813655D01*
X1823840Y816863D01*
X1825587Y821238D01*
X1816853D01*
G01X1838720Y803155D02*
X1838283Y803446D01*
Y804030D01*
X1838720Y804321D01*
X1839157Y804030D01*
Y803446D01*
X1838720Y803155D01*
G01X1851417Y806362D02*
X1852726Y804904D01*
X1854255Y804030D01*
X1856220Y803738D01*
X1858185Y804321D01*
X1859713Y805488D01*
X1860805Y807529D01*
X1861023Y809863D01*
X1860587Y812196D01*
X1859495Y813655D01*
X1857966Y814821D01*
X1856438Y815113D01*
X1854910Y814821D01*
X1852945Y813655D01*
X1853600Y821238D01*
X1859495D01*
G01X1978720Y855888D02*
Y838388D01*
G01X1973698Y855888D02*
X1983742D01*
G01X1996220Y838388D02*
Y846263D01*
X1991853Y855888D01*
G01X2000587D02*
X1996220Y846263D01*
G01X2009353Y838388D02*
Y855888D01*
X2014593D01*
X2016340Y855013D01*
X2017650Y852971D01*
X2018087Y850638D01*
X2017650Y848305D01*
X2016558Y846555D01*
X2014593Y845679D01*
X2009353D01*
G01X2035587Y838388D02*
X2026853D01*
Y855888D01*
X2035587D01*
G01X2032093Y847430D02*
X2026853D01*
G01X1991417Y769088D02*
Y786588D01*
X1995783D01*
X1997530Y785713D01*
X1998840Y784546D01*
X1999932Y782797D01*
X2000805Y780754D01*
X2001023Y777838D01*
X2000805Y774921D01*
X1999932Y772879D01*
X1998840Y771129D01*
X1997530Y769963D01*
X1995783Y769088D01*
X1991417D01*
G01X2009353D02*
Y786588D01*
X2014593D01*
X2016340Y785713D01*
X2017650Y783671D01*
X2018087Y781338D01*
X2017650Y779005D01*
X2016558Y777255D01*
X2014593Y776379D01*
X2009353D01*
G01X1991417Y803738D02*
Y821238D01*
X1995783D01*
X1997530Y820363D01*
X1998840Y819196D01*
X1999932Y817447D01*
X2000805Y815404D01*
X2001023Y812488D01*
X2000805Y809571D01*
X1999932Y807529D01*
X1998840Y805779D01*
X1997530Y804613D01*
X1995783Y803738D01*
X1991417D01*
G01X2009353D02*
Y821238D01*
X2014593D01*
X2016340Y820363D01*
X2017650Y818321D01*
X2018087Y815988D01*
X2017650Y813655D01*
X2016558Y811905D01*
X2014593Y811029D01*
X2009353D01*
G01X2079353Y838388D02*
Y855888D01*
X2084812D01*
X2086558Y855013D01*
X2087650Y853846D01*
X2088087Y851513D01*
X2087650Y849179D01*
X2086340Y847721D01*
X2084812Y846846D01*
X2079353D01*
G01X2084812D02*
X2088087Y838388D01*
G01X2097945Y846263D02*
X2104932D01*
X2104277Y848305D01*
X2103185Y849471D01*
X2101657Y850054D01*
X2100128Y849763D01*
X2098818Y848888D01*
X2097945Y846846D01*
X2097508Y845096D01*
Y843346D01*
X2097945Y841596D01*
X2099037Y839846D01*
X2100347Y838680D01*
X2101875Y838388D01*
X2103403Y838971D01*
X2104932Y840721D01*
G01X2117410Y838388D02*
Y853263D01*
X2117847Y854721D01*
X2118720Y855596D01*
X2120030Y855888D01*
X2121340Y855305D01*
X2121995Y853846D01*
G01X2119375Y848888D02*
X2115008D01*
G01X2136220Y837805D02*
X2135783Y838096D01*
Y838680D01*
X2136220Y838971D01*
X2136657Y838680D01*
Y838096D01*
X2136220Y837805D01*
G01X2166853Y838388D02*
Y855888D01*
X2172093D01*
X2173840Y855013D01*
X2175150Y852971D01*
X2175587Y850638D01*
X2175150Y848305D01*
X2174058Y846555D01*
X2172093Y845679D01*
X2166853D01*
G01X2188720Y838388D02*
Y855888D01*
G01X2210150Y838388D02*
Y850054D01*
G01Y848013D02*
X2209277Y849179D01*
X2207966Y849763D01*
X2206438Y850054D01*
X2204910Y849471D01*
X2203600Y848305D01*
X2202726Y846555D01*
X2202290Y844221D01*
X2202726Y841888D01*
X2203600Y840138D01*
X2204910Y838971D01*
X2206438Y838388D01*
X2207966Y838680D01*
X2209277Y839554D01*
X2210150Y840721D01*
G01X2220008Y838388D02*
Y850054D01*
G01Y847138D02*
X2220882Y848596D01*
X2222192Y849763D01*
X2223938Y850054D01*
X2225466Y849763D01*
X2226777Y848596D01*
X2227432Y846555D01*
Y838388D01*
G01X2237945Y846263D02*
X2244932D01*
X2244277Y848305D01*
X2243185Y849471D01*
X2241657Y850054D01*
X2240128Y849763D01*
X2238818Y848888D01*
X2237945Y846846D01*
X2237508Y845096D01*
Y843346D01*
X2237945Y841596D01*
X2239037Y839846D01*
X2240347Y838680D01*
X2241875Y838388D01*
X2243403Y838971D01*
X2244932Y840721D01*
G01X2123103Y786588D02*
Y769088D01*
X2131837D01*
G01X2140167Y771712D02*
X2141476Y770254D01*
X2143005Y769380D01*
X2144970Y769088D01*
X2146935Y769671D01*
X2148463Y770838D01*
X2149555Y772879D01*
X2149773Y775213D01*
X2149337Y777546D01*
X2148245Y779005D01*
X2146716Y780171D01*
X2145188Y780463D01*
X2143660Y780171D01*
X2141695Y779005D01*
X2142350Y786588D01*
X2148245D01*
G01X2158540Y768505D02*
X2166400Y786588D01*
G01X2175603D02*
Y769088D01*
X2184337D01*
G01X2197033D02*
X2197470Y772879D01*
X2198125Y776088D01*
X2198998Y779005D01*
X2200090Y782213D01*
X2201837Y786588D01*
X2193103D01*
G01X2123103Y821238D02*
Y803738D01*
X2131837D01*
G01X2140167Y806362D02*
X2141476Y804904D01*
X2143005Y804030D01*
X2144970Y803738D01*
X2146935Y804321D01*
X2148463Y805488D01*
X2149555Y807529D01*
X2149773Y809863D01*
X2149337Y812196D01*
X2148245Y813655D01*
X2146716Y814821D01*
X2145188Y815113D01*
X2143660Y814821D01*
X2141695Y813655D01*
X2142350Y821238D01*
X2148245D01*
G01X2158540Y803155D02*
X2166400Y821238D01*
G01X2175603D02*
Y803738D01*
X2184337D01*
G01X2197033D02*
X2197470Y807529D01*
X2198125Y810738D01*
X2198998Y813655D01*
X2200090Y816863D01*
X2201837Y821238D01*
X2193103D01*
G01X2359020Y815404D02*
Y803738D01*
G01Y820071D02*
X2358583Y820363D01*
Y820946D01*
X2359020Y821238D01*
X2359457Y820946D01*
Y820363D01*
X2359020Y820071D01*
G01X2373245Y805779D02*
X2374337Y804613D01*
X2375865Y803738D01*
X2377175D01*
X2378485Y804321D01*
X2379358Y805196D01*
X2379795Y806362D01*
X2379577Y808113D01*
X2378703Y808988D01*
X2374773Y810738D01*
X2373900Y812780D01*
X2374337Y814238D01*
X2375210Y815113D01*
X2376520Y815404D01*
X2377830Y815113D01*
X2379140Y814238D01*
G01X2406498Y803738D02*
Y821238D01*
X2416542Y803738D01*
Y821238D01*
G01X2429020Y803738D02*
X2427273Y804030D01*
X2425745Y805196D01*
X2424435Y806946D01*
X2423561Y808988D01*
X2423125Y811321D01*
Y813655D01*
X2423561Y815988D01*
X2424435Y818030D01*
X2425745Y819779D01*
X2427273Y820946D01*
X2429020Y821238D01*
X2430766Y820946D01*
X2432295Y819779D01*
X2433605Y818030D01*
X2434479Y815988D01*
X2434915Y813655D01*
Y811321D01*
X2434479Y808988D01*
X2433605Y806946D01*
X2432295Y805196D01*
X2430766Y804030D01*
X2429020Y803738D01*
G01X2446520Y821238D02*
Y803738D01*
G01X2441498Y821238D02*
X2451542D01*
G01X2477808Y815404D02*
Y807238D01*
X2478682Y805196D01*
X2479992Y804030D01*
X2481520Y803738D01*
X2483048Y804030D01*
X2484358Y805196D01*
X2485232Y807238D01*
G01Y803738D02*
Y815404D01*
G01X2495745Y805779D02*
X2496837Y804613D01*
X2498365Y803738D01*
X2499675D01*
X2500985Y804321D01*
X2501858Y805196D01*
X2502295Y806362D01*
X2502077Y808113D01*
X2501203Y808988D01*
X2497273Y810738D01*
X2496400Y812780D01*
X2496837Y814238D01*
X2497710Y815113D01*
X2499020Y815404D01*
X2500330Y815113D01*
X2501640Y814238D01*
G01X2513245Y811613D02*
X2520232D01*
X2519577Y813655D01*
X2518485Y814821D01*
X2516957Y815404D01*
X2515428Y815113D01*
X2514118Y814238D01*
X2513245Y812196D01*
X2512808Y810446D01*
Y808696D01*
X2513245Y806946D01*
X2514337Y805196D01*
X2515647Y804030D01*
X2517175Y803738D01*
X2518703Y804321D01*
X2520232Y806071D01*
G01X2537950Y821238D02*
Y803738D01*
G01Y806362D02*
X2537077Y804904D01*
X2535766Y804030D01*
X2534238Y803738D01*
X2532492Y804321D01*
X2531182Y805779D01*
X2530308Y807529D01*
X2530090Y809571D01*
X2530308Y811613D01*
X2531182Y813363D01*
X2532492Y814821D01*
X2534238Y815404D01*
X2535766Y815113D01*
X2536858Y814529D01*
X2537950Y813363D01*
G01X2284217Y837805D02*
X2293823Y850638D01*
G01X2289020Y852971D02*
Y835471D01*
G01X2293823Y837805D02*
X2284217Y850638D01*
G01X2282470Y844221D02*
X2295570D01*
G01X2321182D02*
X2326858D01*
G01X2354217Y838388D02*
Y855888D01*
X2358583D01*
X2360330Y855013D01*
X2361640Y853846D01*
X2362732Y852097D01*
X2363605Y850054D01*
X2363823Y847138D01*
X2363605Y844221D01*
X2362732Y842179D01*
X2361640Y840429D01*
X2360330Y839263D01*
X2358583Y838388D01*
X2354217D01*
G01X2373245Y846263D02*
X2380232D01*
X2379577Y848305D01*
X2378485Y849471D01*
X2376957Y850054D01*
X2375428Y849763D01*
X2374118Y848888D01*
X2373245Y846846D01*
X2372808Y845096D01*
Y843346D01*
X2373245Y841596D01*
X2374337Y839846D01*
X2375647Y838680D01*
X2377175Y838388D01*
X2378703Y838971D01*
X2380232Y840721D01*
G01X2390308Y838388D02*
Y850054D01*
G01Y847138D02*
X2391182Y848596D01*
X2392492Y849763D01*
X2394238Y850054D01*
X2395766Y849763D01*
X2397077Y848596D01*
X2397732Y846555D01*
Y838388D01*
G01X2411520D02*
X2410210Y838680D01*
X2408900Y839846D01*
X2408026Y841888D01*
X2407590Y844221D01*
X2408026Y846555D01*
X2408900Y848596D01*
X2410210Y849763D01*
X2411520Y850054D01*
X2412830Y849763D01*
X2414140Y848596D01*
X2415013Y846555D01*
X2415232Y844221D01*
X2415013Y841888D01*
X2414140Y839846D01*
X2412830Y838680D01*
X2411520Y838388D01*
G01X2429020Y855888D02*
Y838388D01*
G01X2425963Y850054D02*
X2432077D01*
G01X2443245Y846263D02*
X2450232D01*
X2449577Y848305D01*
X2448485Y849471D01*
X2446957Y850054D01*
X2445428Y849763D01*
X2444118Y848888D01*
X2443245Y846846D01*
X2442808Y845096D01*
Y843346D01*
X2443245Y841596D01*
X2444337Y839846D01*
X2445647Y838680D01*
X2447175Y838388D01*
X2448703Y838971D01*
X2450232Y840721D01*
G01X2460745Y840429D02*
X2461837Y839263D01*
X2463365Y838388D01*
X2464675D01*
X2465985Y838971D01*
X2466858Y839846D01*
X2467295Y841012D01*
X2467077Y842763D01*
X2466203Y843638D01*
X2462273Y845388D01*
X2461400Y847430D01*
X2461837Y848888D01*
X2462710Y849763D01*
X2464020Y850054D01*
X2465330Y849763D01*
X2466640Y848888D01*
G01X2499020Y855888D02*
Y838388D01*
G01X2495963Y850054D02*
X2502077D01*
G01X2512808Y838388D02*
Y855888D01*
G01Y847430D02*
X2513900Y848888D01*
X2514992Y849763D01*
X2516738Y850054D01*
X2518048Y849763D01*
X2519577Y848596D01*
X2520232Y846846D01*
Y838388D01*
G01X2537950D02*
Y850054D01*
G01Y848013D02*
X2537077Y849179D01*
X2535766Y849763D01*
X2534238Y850054D01*
X2532710Y849471D01*
X2531400Y848305D01*
X2530526Y846555D01*
X2530090Y844221D01*
X2530526Y841888D01*
X2531400Y840138D01*
X2532710Y838971D01*
X2534238Y838388D01*
X2535766Y838680D01*
X2537077Y839554D01*
X2537950Y840721D01*
G01X2551520Y855888D02*
Y838388D01*
G01X2548463Y850054D02*
X2554577D01*
G01X2586520Y855888D02*
Y838388D01*
G01X2583463Y850054D02*
X2589577D01*
G01X2600308Y838388D02*
Y855888D01*
G01Y847430D02*
X2601400Y848888D01*
X2602492Y849763D01*
X2604238Y850054D01*
X2605548Y849763D01*
X2607077Y848596D01*
X2607732Y846846D01*
Y838388D01*
G01X2621520Y850054D02*
Y838388D01*
G01Y854721D02*
X2621083Y855013D01*
Y855596D01*
X2621520Y855888D01*
X2621957Y855596D01*
Y855013D01*
X2621520Y854721D01*
G01X2635745Y840429D02*
X2636837Y839263D01*
X2638365Y838388D01*
X2639675D01*
X2640985Y838971D01*
X2641858Y839846D01*
X2642295Y841012D01*
X2642077Y842763D01*
X2641203Y843638D01*
X2637273Y845388D01*
X2636400Y847430D01*
X2636837Y848888D01*
X2637710Y849763D01*
X2639020Y850054D01*
X2640330Y849763D01*
X2641640Y848888D01*
G01X2671400Y855888D02*
X2676640D01*
G01X2674020D02*
Y838388D01*
G01X2671400D02*
X2676640D01*
G01X2684970D02*
Y850054D01*
G01Y846846D02*
X2685625Y848305D01*
X2686717Y849471D01*
X2688245Y850054D01*
X2689773Y849471D01*
X2690865Y848305D01*
X2691520Y846846D01*
Y838388D01*
G01Y846846D02*
X2692175Y848305D01*
X2693266Y849471D01*
X2694795Y850054D01*
X2696323Y849471D01*
X2697415Y848305D01*
X2698070Y846555D01*
Y838388D01*
G01X2705090Y832555D02*
Y850054D01*
G01Y847430D02*
X2706182Y848888D01*
X2707273Y849763D01*
X2709020Y850054D01*
X2710548Y849763D01*
X2712077Y848305D01*
X2712732Y846263D01*
X2712950Y844221D01*
X2712732Y842179D01*
X2712077Y840138D01*
X2710766Y838971D01*
X2709020Y838388D01*
X2707492Y838680D01*
X2705963Y839554D01*
X2705090Y840721D01*
G01X2723245Y846263D02*
X2730232D01*
X2729577Y848305D01*
X2728485Y849471D01*
X2726957Y850054D01*
X2725428Y849763D01*
X2724118Y848888D01*
X2723245Y846846D01*
X2722808Y845096D01*
Y843346D01*
X2723245Y841596D01*
X2724337Y839846D01*
X2725647Y838680D01*
X2727175Y838388D01*
X2728703Y838971D01*
X2730232Y840721D01*
G01X2747950Y855888D02*
Y838388D01*
G01Y841012D02*
X2747077Y839554D01*
X2745766Y838680D01*
X2744238Y838388D01*
X2742492Y838971D01*
X2741182Y840429D01*
X2740308Y842179D01*
X2740090Y844221D01*
X2740308Y846263D01*
X2741182Y848013D01*
X2742492Y849471D01*
X2744238Y850054D01*
X2745766Y849763D01*
X2746858Y849179D01*
X2747950Y848013D01*
G01X2765450Y838388D02*
Y850054D01*
G01Y848013D02*
X2764577Y849179D01*
X2763266Y849763D01*
X2761738Y850054D01*
X2760210Y849471D01*
X2758900Y848305D01*
X2758026Y846555D01*
X2757590Y844221D01*
X2758026Y841888D01*
X2758900Y840138D01*
X2760210Y838971D01*
X2761738Y838388D01*
X2763266Y838680D01*
X2764577Y839554D01*
X2765450Y840721D01*
G01X2775308Y838388D02*
Y850054D01*
G01Y847138D02*
X2776182Y848596D01*
X2777492Y849763D01*
X2779238Y850054D01*
X2780766Y849763D01*
X2782077Y848596D01*
X2782732Y846555D01*
Y838388D01*
G01X2800013Y848596D02*
X2798485Y849763D01*
X2797175Y850054D01*
X2795428Y849471D01*
X2794118Y848305D01*
X2793245Y846263D01*
X2793026Y844221D01*
X2793245Y842179D01*
X2794118Y840429D01*
X2795428Y838971D01*
X2797175Y838388D01*
X2798703Y838971D01*
X2800013Y840138D01*
G01X2810745Y846263D02*
X2817732D01*
X2817077Y848305D01*
X2815985Y849471D01*
X2814457Y850054D01*
X2812928Y849763D01*
X2811618Y848888D01*
X2810745Y846846D01*
X2810308Y845096D01*
Y843346D01*
X2810745Y841596D01*
X2811837Y839846D01*
X2813147Y838680D01*
X2814675Y838388D01*
X2816203Y838971D01*
X2817732Y840721D01*
G01X1425733Y-51181D02*
X-29385D01*
G01X-33322Y-47244D02*
G03X-29385Y-51181I3937J0D01*
G01X-33322Y-47244D02*
Y893701D01*
G01X-7874Y102402D02*
Y212205D01*
G01Y102402D02*
G03X0Y94528I7874J0D01*
G01Y212205D02*
G03X-7874I-3937J0D01*
G01Y237402D02*
G03X0I3937J-1D01*
G01X-7874D02*
Y406693D01*
G01X0D02*
G03X-7874I-3937J0D01*
G01Y431890D02*
G03X0I3937J0D01*
G01X-7874D02*
Y601181D01*
G01X0D02*
G03X-7874I-3937J0D01*
G01Y626378D02*
Y795669D01*
G01Y626378D02*
G03X0I3937J0D01*
G01Y795669D02*
G03X-7874I-3937J0D01*
G01Y820866D02*
G03X0I3937J0D01*
G01X-7874Y844488D02*
Y820866D01*
G01X-3937Y848425D02*
G03X-7874Y844488I0J-3937D01*
G01X93307Y848425D02*
X-3937D01*
G01X-29385Y897638D02*
G03X-33322Y893701I0J-3937D01*
G01X-29385Y897638D02*
X93307D01*
G01X98425Y94528D02*
X0D01*
G01X1400000Y36220D02*
G03X1398031Y38189I-1969J0D01*
G01X1396654D01*
G02X1394685Y40157I0J1969D01*
G01Y71654D01*
G02X1396654Y73622I1969J-1D01*
G01X1398031D01*
G03X1400000Y75591I0J1969D01*
G01Y836614D01*
G03X1396063Y840551I-3937J0D01*
G01X1368504D01*
G02X1363386Y845669I0J5118D01*
G01Y871654D01*
G03X1361417Y873622I-1969J-1D01*
G01X1358268D01*
G02X1356299Y875591I0J1969D01*
G01Y892521D01*
X1352363Y897638D01*
X1218110D01*
X1214173Y892520D01*
Y875984D01*
G02X1205512I-4331J0D01*
G01Y892520D01*
X1201575Y897638D01*
X1029528D01*
X1025591Y892520D01*
Y875591D01*
G02X1023622Y873622I-1969J0D01*
G01X1020472D01*
G03X1018504Y871654I0J-1968D01*
G01Y845669D01*
G02X1013386Y840551I-5118J0D01*
G01X1008433D01*
G03X988748Y820866I0J-19685D01*
G01Y650669D01*
G02X983748Y645669I-5000J0D01*
G01X926819D01*
G02X921819Y650669I0J5000D01*
G01Y820866D01*
G03X902134Y840551I-19685J0D01*
G01X872441D01*
G02X867323Y845669I0J5118D01*
G01Y871654D01*
G03X865354Y873622I-1969J-1D01*
G01X862205D01*
G02X860236Y875591I0J1969D01*
G01Y892521D01*
X856300Y897638D01*
X722048D01*
X718110Y892519D01*
Y875984D01*
G02X709449I-4331J0D01*
G01Y892520D01*
X705512Y897638D01*
X533465D01*
X529528Y892520D01*
Y875591D01*
G02X527559Y873622I-1969J0D01*
G01X524409D01*
G03X522441Y871654I0J-1968D01*
G01Y845669D01*
G02X517323Y840551I-5118J0D01*
G01X455118D01*
G02X450000Y845669I0J5118D01*
G01Y871654D01*
G03X448031Y873622I-1968J0D01*
G01X444882D01*
G02X442913Y875591I0J1969D01*
G01Y892521D01*
X438977Y897638D01*
X304725D01*
X300787Y892519D01*
Y875984D01*
G02X292126I-4331J0D01*
G01Y892521D01*
X288190Y897638D01*
X116142D01*
X112205Y892520D01*
Y875591D01*
G02X110236Y873622I-1969J0D01*
G01X107087D01*
G03X105118Y871654I0J-1969D01*
G01Y845669D01*
G02X100000Y840551I-5118J0D01*
G01X3937D01*
G03X0Y836614I0J-3937D01*
G01Y110276D01*
G03X7874Y102402I7874J0D01*
G01X196654D01*
G02X204528Y94528I0J-7874D01*
G01Y7874D01*
G03X212402Y0I7874J0D01*
G01X471014D01*
G02X478888Y-7874I0J-7874D01*
G01Y-11811D01*
G03X486762Y-19685I7874J0D01*
G01X1302165D01*
G03X1306102Y-15748I0J3937D01*
G01Y-3937D01*
G02X1310039Y0I3937J0D01*
G01X1396063D01*
G03X1400000Y3937I0J3937D01*
G01Y36220D01*
G01X93307Y848425D02*
G03X97244Y852362I0J3937D01*
G01Y893701D02*
Y852362D01*
G01Y893701D02*
G03X93307Y897638I-3937J0D01*
G01X192717Y94528D02*
X123622D01*
G01Y102402D02*
G03Y94528I0J-3937D01*
G01X98425D02*
G03Y102402I0J3937D01*
G01X196654Y0D02*
G03X204528Y-7874I7874J0D01*
G01X196654Y0D02*
Y29961D01*
G01X204528D02*
G03X196654I-3937J0D01*
G01Y55157D02*
Y90591D01*
G01Y55157D02*
G03X204528I3937J0D01*
G01X196654Y90591D02*
G03X192717Y94528I-3937J0D01*
G01X232077Y-7874D02*
G03Y0I0J3937D01*
G01Y-7874D02*
X204528D01*
G01X434439D02*
X257274D01*
G01Y0D02*
G03Y-7874I0J-3937D01*
G01X365945Y38188D02*
G03X367914Y40156I0J1969D01*
G01X354134D02*
G03X356103Y38188I1969J1D01*
G01D02*
X365945D01*
G01X354134Y71653D02*
Y40156D01*
G01X367914Y71653D02*
G03X365945Y73621I-1969J-1D01*
G01X356103D02*
G03X354134Y71653I0J-1969D01*
G01X365945Y73621D02*
X356103D01*
G01X367914Y40156D02*
Y71653D01*
G01X434439Y-7874D02*
G03Y0I0J3937D01*
G01X471014Y-15748D02*
G03X463140Y-7874I-7874J0D01*
G01D02*
X459636D01*
G01Y0D02*
G03Y-7874I0J-3937D01*
G01X707234Y-27559D02*
X478888D01*
G01X471014Y-19685D02*
G03X478888Y-27559I7874J0D01*
G01X471014Y-19685D02*
Y-15748D01*
G01X870226Y-27559D02*
X732431D01*
G01Y-19685D02*
G03Y-27559I0J-3937D01*
G01X707234D02*
G03Y-19685I0J3937D01*
G01X870226Y-27559D02*
G03Y-19685I1J3937D01*
G01X1072589Y-27559D02*
X895423D01*
G01Y-19685D02*
G03Y-27559I0J-3937D01*
G01X1072589D02*
G03Y-19685I0J3937D01*
G01X1097785D02*
G03Y-27559I1J-3937D01*
G01X1336086Y-8662D02*
X1318701D01*
G03X1314764Y-12599I0J-3937D01*
G01Y-23622D01*
G02X1310827Y-27559I-3937J0D01*
G01X1097785D01*
G01X1336086Y-8662D02*
G03Y-1I0J4330D01*
G01X1361283D02*
G03Y-8662I0J-4330D01*
G01X1407874Y13026D02*
Y-4725D01*
G02X1403937Y-8662I-3937J0D01*
G01X1361283D01*
G01X1403937Y848425D02*
X1375197D01*
G01X1371260Y852362D02*
G03X1375197Y848425I3937J0D01*
G01X1371260Y852362D02*
Y893701D01*
G01X1375197Y897638D02*
G03X1371260Y893701I0J-3937D01*
G01X1375197Y897638D02*
X1425733D01*
G01X1407874Y30709D02*
Y219685D01*
G01X1400000Y30709D02*
G03X1407874I3937J0D01*
G01Y13026D02*
G03X1400000I-3937J-1D01*
G01X1407874Y219685D02*
G03X1400000I-3937J0D01*
G01Y244882D02*
G03X1407874I3937J0D01*
G01Y414173D02*
Y244882D01*
G01Y608661D02*
Y439370D01*
G01X1400000D02*
G03X1407874I3937J0D01*
G01Y414173D02*
G03X1400000I-3937J0D01*
G01X1407874Y608661D02*
G03X1400000I-3937J0D01*
G01Y626378D02*
G03X1407874I3937J0D01*
G01Y795669D02*
Y626378D01*
G01Y795669D02*
G03X1400000I-3937J0D01*
G01Y820866D02*
G03X1407874I3937J0D01*
G01Y844488D02*
Y820866D01*
G01Y844488D02*
G03X1403937Y848425I-3937J0D01*
G01X1429670Y893701D02*
Y-47244D01*
G01X1425733Y-51181D02*
G03X1429670Y-47244I0J3937D01*
G01Y893701D02*
G03X1425733Y897638I-3937J0D01*
G54D13*
G01X85848Y251712D02*
X110259Y227302D01*
G01X87040Y252360D02*
X111082Y228318D01*
G01X87040Y252360D02*
X111082Y228318D01*
G01X85848Y251712D02*
X110259Y227302D01*
G01X89602Y270247D02*
X92997Y286216D01*
G01X90932Y270247D02*
X94327Y286216D01*
G01X90991Y263722D02*
X89602Y270247D01*
G01X92213Y264229D02*
X90932Y270247D01*
G01X108376Y236952D02*
X90991Y263722D01*
G01X109316Y237892D02*
X92213Y264229D01*
G01X90932Y270247D02*
X94327Y286216D01*
G01X89602Y270247D02*
X92997Y286216D01*
G01X92213Y264229D02*
X90932Y270247D01*
G01X90991Y263722D02*
X89602Y270247D01*
G01X109316Y237892D02*
X92213Y264229D01*
G01X108376Y236952D02*
X90991Y263722D01*
G01X82350Y268151D02*
X85848Y251712D01*
G01X83680Y268151D02*
X87040Y252360D01*
G01X85657Y283713D02*
X82350Y268151D01*
G01X86987Y283713D02*
X83680Y268151D01*
G01D02*
X87040Y252360D01*
G01X82350Y268151D02*
X85848Y251712D01*
G01X86987Y283713D02*
X83680Y268151D01*
G01X85657Y283713D02*
X82350Y268151D01*
G01X80916Y308512D02*
X76021Y316048D01*
G01X81856Y309452D02*
X77243Y316555D01*
G01X87245Y304403D02*
X80916Y308512D01*
G01X88185Y305343D02*
X81856Y309452D01*
G01X90049Y300086D02*
X87245Y304403D01*
G01X91271Y300592D02*
X88185Y305343D01*
G01X92997Y286216D02*
X90049Y300086D01*
G01X94327Y286216D02*
X91271Y300592D01*
G01X81856Y309452D02*
X77243Y316555D01*
G01X80916Y308512D02*
X76021Y316048D01*
G01X88185Y305343D02*
X81856Y309452D01*
G01X87245Y304403D02*
X80916Y308512D01*
G01X91271Y300592D02*
X88185Y305343D01*
G01X90049Y300086D02*
X87245Y304403D01*
G01X94327Y286216D02*
X91271Y300592D01*
G01X92997Y286216D02*
X90049Y300086D01*
G01X83090Y295798D02*
X85657Y283713D01*
G01X84250Y296595D02*
X86987Y283713D01*
G01X75699Y300600D02*
X83090Y295798D01*
G01X76522Y301616D02*
X84250Y296595D01*
G01X73764Y302535D02*
X75699Y300600D01*
G01X74780Y303358D02*
X76522Y301616D01*
G01X72280Y304820D02*
X73764Y302535D01*
G01X73503Y305325D02*
X74780Y303358D01*
G01X68351Y323458D02*
X72280Y304820D01*
G01X69675Y323482D02*
X73503Y305325D01*
G01X84250Y296595D02*
X86987Y283713D01*
G01X83090Y295798D02*
X85657Y283713D01*
G01X76522Y301616D02*
X84250Y296595D01*
G01X75699Y300600D02*
X83090Y295798D01*
G01X74780Y303358D02*
X76522Y301616D01*
G01X73764Y302535D02*
X75699Y300600D01*
G01X73503Y305325D02*
X74780Y303358D01*
G01X72280Y304820D02*
X73764Y302535D01*
G01X69675Y323482D02*
X73503Y305325D01*
G01X68351Y323458D02*
X72280Y304820D01*
G01X75173Y320036D02*
Y321518D01*
G01X76473Y320173D02*
Y321522D01*
G01X76021Y316048D02*
X75173Y320036D01*
G01X77243Y316555D02*
X76473Y320173D01*
G01D02*
Y321522D01*
G01X75173Y320036D02*
Y321518D01*
G01X77243Y316555D02*
X76473Y320173D01*
G01X76021Y316048D02*
X75173Y320036D01*
G01X68910Y326680D02*
X68351Y323458D01*
G01X70146Y326194D02*
X69675Y323482D01*
G01X69578Y327707D02*
X68910Y326680D01*
G01X70518Y326766D02*
X70146Y326194D01*
G01X79488Y334140D02*
X69578Y327707D01*
G01X80428Y333200D02*
X70518Y326766D01*
G01X80719Y336036D02*
X79488Y334140D01*
G01X81941Y335530D02*
X80428Y333200D01*
G01X81226Y338421D02*
X80719Y336036D01*
G01X82526Y338284D02*
X81941Y335530D01*
G01X81226Y342908D02*
Y338421D01*
G01X82526Y342908D02*
Y338284D01*
G01X70146Y326194D02*
X69675Y323482D01*
G01X68910Y326680D02*
X68351Y323458D01*
G01X70518Y326766D02*
X70146Y326194D01*
G01X69578Y327707D02*
X68910Y326680D01*
G01X80428Y333200D02*
X70518Y326766D01*
G01X79488Y334140D02*
X69578Y327707D01*
G01X81941Y335530D02*
X80428Y333200D01*
G01X80719Y336036D02*
X79488Y334140D01*
G01X82526Y338284D02*
X81941Y335530D01*
G01X81226Y338421D02*
X80719Y336036D01*
G01X82526Y342908D02*
Y338284D01*
G01X81226Y342908D02*
Y338421D01*
G01X122937Y227495D02*
X108376Y236952D01*
G01X123443Y228717D02*
X109316Y237892D01*
G01X189623Y213319D02*
X122937Y227495D01*
G01X189623Y214649D02*
X123443Y228717D01*
G01D02*
X109316Y237892D01*
G01X122937Y227495D02*
X108376Y236952D01*
G01X189623Y214649D02*
X123443Y228717D01*
G01X189623Y213319D02*
X122937Y227495D01*
G01X110259Y227302D02*
X145925Y204140D01*
G01X111082Y228318D02*
X146431Y205362D01*
G01X111082Y228318D02*
X146431Y205362D01*
G01X110259Y227302D02*
X145925Y204140D01*
G01D02*
X184890Y195858D01*
G01X146431Y205362D02*
X184890Y197188D01*
G01X146431Y205362D02*
X184890Y197188D01*
G01X145925Y204140D02*
X184890Y195858D01*
G01X194296Y197858D02*
X207914Y194963D01*
G01X194296Y199188D02*
X207914Y196293D01*
G01X184890Y195858D02*
X194296Y197858D01*
G01X184890Y197188D02*
X194296Y199188D01*
G01D02*
X207914Y196293D01*
G01X194296Y197858D02*
X207914Y194963D01*
G01X184890Y197188D02*
X194296Y199188D01*
G01X184890Y195858D02*
X194296Y197858D01*
G01X220325Y219838D02*
X189623Y213319D01*
G01X220056Y221110D02*
X189623Y214649D01*
G01X220056Y221110D02*
X189623Y214649D01*
G01X220325Y219838D02*
X189623Y213319D01*
G01X220325Y219838D02*
X189623Y213319D01*
G01X194666Y810866D02*
X190567Y816720D01*
G01X193856Y814291D02*
X195600Y811800D01*
G01X191798Y817230D02*
X193856Y814291D01*
G01X221769Y791888D02*
X194666Y810866D01*
G01X195600Y811800D02*
X222279Y793119D01*
G01X195600Y811800D02*
X222279Y793119D01*
G01X221769Y791888D02*
X194666Y810866D01*
G01X193856Y814291D02*
X195600Y811800D01*
G01X194666Y810866D02*
X190567Y816720D01*
G01X191798Y817230D02*
X193856Y814291D01*
G01X194666Y810866D02*
X190567Y816720D01*
G01X191870Y827192D02*
Y828500D01*
G01X193170Y827675D02*
Y827192D01*
G01X191315Y825855D02*
G03X191870Y827192I-1336J1338D01*
G01X193170D02*
G02X192235Y824935I-3192J0D01*
G01X190000Y822678D02*
G02X191315Y825855I4492J1D01*
G01X192235Y824935D02*
G03X191300Y822678I2257J-2257D01*
G01X190000Y819939D02*
Y822678D01*
G01X191300D02*
Y820053D01*
G01X190567Y816720D02*
X190000Y819939D01*
G01X191300Y820053D02*
X191798Y817230D01*
G01X191300Y820053D02*
X191798Y817230D01*
G01X190567Y816720D02*
X190000Y819939D01*
G01X191300Y822678D02*
Y820053D01*
G01X190000Y819939D02*
Y822678D01*
G01X192235Y824935D02*
G03X191300Y822678I2257J-2257D01*
G01X190000D02*
G02X191315Y825855I4492J1D01*
G01X193170Y827192D02*
G02X192235Y824935I-3192J0D01*
G01X191315Y825855D02*
G03X191870Y827192I-1336J1338D01*
G01X193170Y827675D02*
Y827192D01*
G01X191870D02*
Y828500D01*
G01X222353Y198033D02*
X242046Y210823D01*
G01X221847Y199255D02*
X241540Y212045D01*
G01X207914Y194963D02*
X222353Y198033D01*
G01X207914Y196293D02*
X221847Y199255D01*
G01D02*
X241540Y212045D01*
G01X222353Y198033D02*
X242046Y210823D01*
G01X207914Y196293D02*
X221847Y199255D01*
G01X207914Y194963D02*
X222353Y198033D01*
G01X220325Y221168D02*
X220056Y221111D01*
G01X237584Y216170D02*
X220325Y219838D01*
G01X237584Y217500D02*
X220325Y221168D01*
G01D02*
X220056Y221111D01*
G01X237584Y217500D02*
X220325Y221168D01*
G01X237584Y216170D02*
X220325Y219838D01*
G01X230800Y735635D02*
Y770900D01*
G01X229500Y770641D02*
Y735300D01*
G01X235125Y710876D02*
X230778Y735510D01*
G01X229497Y735285D02*
X233844Y710650D01*
G01X229497Y735285D02*
X233844Y710650D01*
G01X235125Y710876D02*
X230778Y735510D01*
G01X229500Y770641D02*
Y735300D01*
G01X230800Y735635D02*
Y770900D01*
G01X236566Y810066D02*
X229665Y819923D01*
G01X229426Y799309D02*
X236400Y794427D01*
G01X230173Y800375D02*
X236910Y795658D01*
G01X219031Y806588D02*
X229426Y799309D01*
G01X226258Y803117D02*
X230173Y800375D01*
G01X223694Y804912D02*
X224724Y805094D01*
G01X222342Y805858D02*
X223694Y804912D01*
G01X219778Y807654D02*
X220809Y807835D01*
G01X216601Y808291D02*
X219032Y806589D01*
G01X217535Y809225D02*
X219778Y807654D01*
G01X204468Y825619D02*
X216601Y808291D01*
G01X205768Y826029D02*
X217535Y809225D01*
G01X224066Y810066D02*
X242246Y797336D01*
G01X232566Y805702D02*
X233918Y804756D01*
G01X230002Y807497D02*
X231033Y807679D01*
G01X225000Y811000D02*
X230002Y807497D01*
G01X217067Y820063D02*
X224066Y810066D01*
G01X218367Y820473D02*
X225000Y811000D01*
G01X236566Y810066D02*
X229665Y819923D01*
G01X230173Y800375D02*
X236910Y795658D01*
G01X229426Y799309D02*
X236400Y794427D01*
G01X226258Y803117D02*
X230173Y800375D01*
G01X219031Y806588D02*
X229426Y799309D01*
G01X223694Y804912D02*
X224724Y805094D01*
G01X219031Y806588D02*
X229426Y799309D01*
G01X222342Y805858D02*
X223694Y804912D01*
G01X219031Y806588D02*
X229426Y799309D01*
G01X219778Y807654D02*
X220809Y807835D01*
G01X219031Y806588D02*
X229426Y799309D01*
G01X217535Y809225D02*
X219778Y807654D01*
G01X216601Y808291D02*
X219032Y806589D01*
G01X205768Y826029D02*
X217535Y809225D01*
G01X204468Y825619D02*
X216601Y808291D01*
G01X224066Y810066D02*
X242246Y797336D01*
G01X224066Y810066D02*
X242246Y797336D01*
G01X232566Y805702D02*
X233918Y804756D01*
G01X224066Y810066D02*
X242246Y797336D01*
G01X230002Y807497D02*
X231033Y807679D01*
G01X224066Y810066D02*
X242246Y797336D01*
G01X225000Y811000D02*
X230002Y807497D01*
G01X224066Y810066D02*
X242246Y797336D01*
G01X218367Y820473D02*
X225000Y811000D01*
G01X217067Y820063D02*
X224066Y810066D01*
G01X281990Y781269D02*
X221769Y791888D01*
G01X222279Y793119D02*
X282500Y782500D01*
G01X222279Y793119D02*
X282500Y782500D01*
G01X281990Y781269D02*
X221769Y791888D01*
G01X230965Y820333D02*
Y827675D01*
G01X229665Y819923D02*
Y827675D01*
G01X237500Y811000D02*
X230965Y820333D01*
G01X204468Y827675D02*
Y825619D01*
G01X205768Y827675D02*
Y826029D01*
G01X217067Y827675D02*
Y820063D01*
G01X218367Y827675D02*
Y820473D01*
G01X229665Y819923D02*
Y827675D01*
G01X230965Y820333D02*
Y827675D01*
G01X237500Y811000D02*
X230965Y820333D01*
G01X205768Y827675D02*
Y826029D01*
G01X204468Y827675D02*
Y825619D01*
G01X218367Y827675D02*
Y820473D01*
G01X217067Y827675D02*
Y820063D01*
G01X270954Y223263D02*
X237584Y216170D01*
G01X270954Y224593D02*
X237584Y217500D01*
G01X270954Y224593D02*
X237584Y217500D01*
G01X270954Y223263D02*
X237584Y216170D01*
G01X242046Y210823D02*
X270813Y216937D01*
G01X241540Y212045D02*
X270813Y218267D01*
G01X241540Y212045D02*
X270813Y218267D01*
G01X242046Y210823D02*
X270813Y216937D01*
G01X235216Y710656D02*
G02X235125Y710875I450J315D01*
G01X233844Y710650D02*
G03X234150Y709910I1822J320D01*
G01X241760Y701309D02*
X235216Y710656D01*
G01X234150Y709910D02*
X240694Y700562D01*
G01X251549Y694454D02*
X241760Y701309D01*
G01X241014Y700244D02*
X250803Y693388D01*
G01X241012Y700244D02*
X241014D01*
G01X251769Y694363D02*
G02X251549Y694454I95J542D01*
G01X250803Y693388D02*
G03X251543Y693082I1061J1517D01*
G01X267699Y691554D02*
X251769Y694363D01*
G01X251543Y693082D02*
X267473Y690273D01*
G01X251543Y693082D02*
X267473Y690273D01*
G01X267699Y691554D02*
X251769Y694363D01*
G01X250803Y693388D02*
G03X251543Y693082I1061J1517D01*
G01X251769Y694363D02*
G02X251549Y694454I95J542D01*
G01X241014Y700244D02*
X250803Y693388D01*
G01X251549Y694454D02*
X241760Y701309D01*
G01X241012Y700244D02*
X241014D01*
G01X251549Y694454D02*
X241760Y701309D01*
G01X234150Y709910D02*
X240694Y700562D01*
G01X241760Y701309D02*
X235216Y710656D01*
G01X233844Y710650D02*
G03X234150Y709910I1822J320D01*
G01X235216Y710656D02*
G02X235125Y710875I450J315D01*
G01X270589Y809750D02*
X264311Y818717D01*
G01X259066Y807566D02*
X251712Y818070D01*
G01X260000Y808500D02*
X253012Y818480D01*
G01X267522Y801645D02*
X259066Y807566D01*
G01X268032Y802876D02*
X260000Y808500D01*
G01X270589Y809750D02*
X264311Y818717D01*
G01X260000Y808500D02*
X253012Y818480D01*
G01X259066Y807566D02*
X251712Y818070D01*
G01X268032Y802876D02*
X260000Y808500D01*
G01X267522Y801645D02*
X259066Y807566D01*
G01X253325Y799919D02*
X237500Y811000D01*
G01X252815Y798688D02*
X236566Y810066D01*
G01X266001Y797684D02*
X253325Y799919D01*
G01X334190Y784340D02*
X252815Y798688D01*
G01X334190Y784340D02*
X252815Y798688D01*
G01X334190Y784340D02*
X252815Y798688D01*
G01X236400Y794427D02*
X326482Y778543D01*
G01X236910Y795658D02*
X326992Y779774D01*
G01X242246Y797336D02*
X326073Y782555D01*
G01X242756Y798567D02*
X326583Y783786D01*
G01X236482Y802960D02*
X242756Y798567D01*
G01X233918Y804756D02*
X234948Y804937D01*
G01X252815Y798688D02*
X236566Y810066D01*
G01X253325Y799919D02*
X237500Y811000D01*
G01X334190Y784340D02*
X252815Y798688D01*
G01X266001Y797684D02*
X253325Y799919D01*
G01X236910Y795658D02*
X326992Y779774D01*
G01X236400Y794427D02*
X326482Y778543D01*
G01X242756Y798567D02*
X326583Y783786D01*
G01X242246Y797336D02*
X326073Y782555D01*
G01X236482Y802960D02*
X242756Y798567D01*
G01X233918Y804756D02*
X234948Y804937D01*
G01X265611Y819127D02*
Y827675D01*
G01X264311Y818717D02*
Y827675D01*
G01X271523Y810684D02*
X265611Y819127D01*
G01X251712Y818070D02*
Y827675D01*
G01X253012Y818480D02*
Y827675D01*
G01X264311Y818717D02*
Y827675D01*
G01X265611Y819127D02*
Y827675D01*
G01X271523Y810684D02*
X265611Y819127D01*
G01X253012Y818480D02*
Y827675D01*
G01X251712Y818070D02*
Y827675D01*
G01X283372Y220625D02*
X270954Y223263D01*
G01X283372Y221955D02*
X270954Y224593D01*
G01X308869Y226045D02*
X283372Y220625D01*
G01X308869Y227375D02*
X283372Y221955D01*
G01D02*
X270954Y224593D01*
G01X283372Y220625D02*
X270954Y223263D01*
G01X308869Y227375D02*
X283372Y221955D01*
G01X308869Y226045D02*
X283372Y220625D01*
G01X296763Y217207D02*
X302057Y216083D01*
G01X296763Y218537D02*
X302057Y217413D01*
G01X283156Y214315D02*
X296763Y217207D01*
G01X283156Y215645D02*
X296763Y218537D01*
G01X270813Y216937D02*
X283156Y214315D01*
G01X270813Y218267D02*
X283156Y215645D01*
G01X296763Y218537D02*
X302057Y217413D01*
G01X296763Y217207D02*
X302057Y216083D01*
G01X283156Y215645D02*
X296763Y218537D01*
G01X283156Y214315D02*
X296763Y217207D01*
G01X270813Y218267D02*
X283156Y215645D01*
G01X270813Y216937D02*
X283156Y214315D01*
G01X267891Y691554D02*
G02X267699I-96J542D01*
G01X267473Y690273D02*
G03X268117I322J1823D01*
G01X285979Y694743D02*
X267891Y691554D01*
G01X268117Y690273D02*
X286205Y693462D01*
G01X286621Y694743D02*
G03X285979I-321J-1822D01*
G01X286205Y693462D02*
G02X286395I95J-541D01*
G01X322939Y688339D02*
X286621Y694743D01*
G01X286395Y693462D02*
X322713Y687058D01*
G01X286395Y693462D02*
X322713Y687058D01*
G01X322939Y688339D02*
X286621Y694743D01*
G01X286205Y693462D02*
G02X286395I95J-541D01*
G01X286621Y694743D02*
G03X285979I-321J-1822D01*
G01X268117Y690273D02*
X286205Y693462D01*
G01X285979Y694743D02*
X267891Y691554D01*
G01X267473Y690273D02*
G03X268117I322J1823D01*
G01X267891Y691554D02*
G02X267699I-96J542D01*
G01X294182Y772732D02*
X281990Y781269D01*
G01X282500Y782500D02*
X294692Y773963D01*
G01X332484Y765979D02*
X294182Y772732D01*
G01X294692Y773963D02*
X332994Y767210D01*
G01X294692Y773963D02*
X332994Y767210D01*
G01X332484Y765979D02*
X294182Y772732D01*
G01X282500Y782500D02*
X294692Y773963D01*
G01X294182Y772732D02*
X281990Y781269D01*
G01X281566Y812566D02*
X276909Y819218D01*
G01X282500Y813500D02*
X278209Y819628D01*
G01X290090Y806598D02*
X281566Y812566D01*
G01X290600Y807829D02*
X282500Y813500D01*
G01X311017Y802907D02*
X290090Y806598D01*
G01X298746Y806393D02*
X290600Y807829D01*
G01X282500Y813500D02*
X278209Y819628D01*
G01X281566Y812566D02*
X276909Y819218D01*
G01X290600Y807829D02*
X282500Y813500D01*
G01X290090Y806598D02*
X281566Y812566D01*
G01X298746Y806393D02*
X290600Y807829D01*
G01X311017Y802907D02*
X290090Y806598D01*
G01X311017Y802907D02*
X290090Y806598D01*
G01X311017Y802907D02*
X290090Y806598D01*
G01X311017Y802907D02*
X290090Y806598D01*
G01X279143Y805349D02*
X271523Y810684D01*
G01X278633Y804118D02*
X270589Y809750D01*
G01X283292Y804617D02*
X279143Y805349D01*
G01X295564Y801132D02*
X278633Y804118D01*
G01X288000Y803787D02*
X286375Y804074D01*
G01X295564Y801132D02*
X278633Y804118D01*
G01X292171Y803052D02*
X291082Y803244D01*
G01X295564Y801132D02*
X278633Y804118D01*
G01X295790Y802414D02*
X292171Y803052D01*
G01X295564Y801132D02*
X278633Y804118D01*
G01X315486Y798941D02*
X295790Y802414D01*
G01X328685Y795292D02*
X295564Y801132D01*
G01X328685Y795292D02*
X295564Y801132D01*
G01X300333Y795859D02*
X267522Y801645D01*
G01X292242Y798607D02*
X268032Y802876D01*
G01X296949Y797777D02*
X295324Y798063D01*
G01X301157Y797035D02*
X300032Y797233D01*
G01X301157Y797035D02*
X300032Y797233D01*
G01X278633Y804118D02*
X270589Y809750D01*
G01X279143Y805349D02*
X271523Y810684D01*
G01X295564Y801132D02*
X278633Y804118D01*
G01X283292Y804617D02*
X279143Y805349D01*
G01X288000Y803787D02*
X286375Y804074D01*
G01X292171Y803052D02*
X291082Y803244D01*
G01X295790Y802414D02*
X292171Y803052D01*
G01X328685Y795292D02*
X295564Y801132D01*
G01X315486Y798941D02*
X295790Y802414D01*
G01X292242Y798607D02*
X268032Y802876D01*
G01X300333Y795859D02*
X267522Y801645D01*
G01X296949Y797777D02*
X295324Y798063D01*
G01X300333Y795859D02*
X267522Y801645D01*
G01X301157Y797035D02*
X300032Y797233D01*
G01X300333Y795859D02*
X267522Y801645D01*
G01X270708Y796854D02*
X269084Y797140D01*
G01X334700Y785571D02*
X273791Y796310D01*
G01X270708Y796854D02*
X269084Y797140D01*
G01X334700Y785571D02*
X273791Y796310D01*
G01X276909Y819218D02*
Y827200D01*
G01X278209Y819628D02*
Y827200D01*
G01Y819628D02*
Y827200D01*
G01X276909Y819218D02*
Y827200D01*
G01X360567Y215055D02*
X308869Y226045D01*
G01X361073Y216277D02*
X308869Y227375D01*
G01X361073Y216277D02*
X308869Y227375D01*
G01X360567Y215055D02*
X308869Y226045D01*
G01X312847Y219706D02*
X359930Y209697D01*
G01X312847Y218376D02*
X336137Y213425D01*
G01X312847Y219706D02*
X359930Y209697D01*
G01X302057Y216083D02*
X312847Y218376D01*
G01X302057Y217413D02*
X312847Y219706D01*
G01D02*
X359930Y209697D01*
G01X312847Y218376D02*
X336137Y213425D01*
G01X302057Y217413D02*
X312847Y219706D01*
G01X302057Y216083D02*
X312847Y218376D01*
G01X323131Y688339D02*
G02X322939I-96J542D01*
G01X322713Y687058D02*
G03X323357I322J1823D01*
G01X353779Y693743D02*
X323131Y688339D01*
G01X323357Y687058D02*
X354005Y692462D01*
G01X323357Y687058D02*
X354005Y692462D01*
G01X353779Y693743D02*
X323131Y688339D01*
G01X322713Y687058D02*
G03X323357I322J1823D01*
G01X323131Y688339D02*
G02X322939I-96J542D01*
G01X326482Y778543D02*
X631921Y564672D01*
G01X326992Y779774D02*
X632760Y565672D01*
G01X326073Y782555D02*
X634658Y566481D01*
G01X326583Y783786D02*
X635592Y567415D01*
G01X326992Y779774D02*
X632760Y565672D01*
G01X326482Y778543D02*
X631921Y564672D01*
G01X326583Y783786D02*
X635592Y567415D01*
G01X326073Y782555D02*
X634658Y566481D01*
G01X625292Y560956D02*
X332484Y765979D01*
G01X332994Y767210D02*
X626226Y561890D01*
G01X332994Y767210D02*
X626226Y561890D01*
G01X625292Y560956D02*
X332484Y765979D01*
G01X327303Y822795D02*
X336566Y809566D01*
G01X327303Y822795D02*
X336566Y809566D01*
G01X327303Y822795D02*
X336566Y809566D01*
G01X333989Y806670D02*
X318865Y817283D01*
G01X325249Y814391D02*
X323899Y815339D01*
G01X326280Y814572D02*
X325249Y814391D01*
G01X334735Y807735D02*
X327811Y812594D01*
G01X327303Y822795D02*
X336566Y809566D01*
G01X333989Y806670D02*
X318865Y817283D01*
G01X333989Y806670D02*
X318865Y817283D01*
G01X325249Y814391D02*
X323899Y815339D01*
G01X333989Y806670D02*
X318865Y817283D01*
G01X326280Y814572D02*
X325249Y814391D01*
G01X333989Y806670D02*
X318865Y817283D01*
G01X334735Y807735D02*
X327811Y812594D01*
G01X333989Y806670D02*
X318865Y817283D01*
G01X303453Y805563D02*
X301828Y805849D01*
G01X308160Y804733D02*
X306535Y805019D01*
G01X311243Y804189D02*
X308160Y804733D01*
G01X334490Y798769D02*
X311017Y802907D01*
G01X335000Y800000D02*
X311243Y804189D01*
G01X303453Y805563D02*
X301828Y805849D01*
G01X308160Y804733D02*
X306535Y805019D01*
G01X311243Y804189D02*
X308160Y804733D01*
G01X335000Y800000D02*
X311243Y804189D01*
G01X334490Y798769D02*
X311017Y802907D01*
G01X328911Y796573D02*
X315486Y798941D01*
G01X335000Y795500D02*
X328911Y796573D01*
G01X334490Y794269D02*
X328685Y795292D01*
G01X305003Y795035D02*
X300333Y795859D01*
G01X305229Y796317D02*
X301157Y797035D01*
G01X332575Y790174D02*
X305003Y795035D01*
G01X333085Y791405D02*
X305229Y796317D01*
G01X644066Y572066D02*
X332575Y790174D01*
G01X645000Y573000D02*
X333085Y791405D01*
G01X328911Y796573D02*
X315486Y798941D01*
G01X334490Y794269D02*
X328685Y795292D01*
G01X335000Y795500D02*
X328911Y796573D01*
G01X305003Y795035D02*
X300333Y795859D01*
G01X305229Y796317D02*
X301157Y797035D01*
G01X305003Y795035D02*
X300333Y795859D01*
G01X333085Y791405D02*
X305229Y796317D01*
G01X332575Y790174D02*
X305003Y795035D01*
G01X645000Y573000D02*
X333085Y791405D01*
G01X644066Y572066D02*
X332575Y790174D01*
G01X331776Y818674D02*
X332722Y817323D01*
G01X328603Y823205D02*
X329980Y821238D01*
G01X328603Y827675D02*
Y823205D01*
G01X327303Y827675D02*
Y822795D01*
G01X314704Y823224D02*
Y827675D01*
G01X316004Y823635D02*
Y827675D01*
G01X318865Y817283D02*
X314704Y823224D01*
G01X319799Y818216D02*
X316004Y823635D01*
G01X321337Y817137D02*
X319799Y818216D01*
G01X322367Y817318D02*
X321337Y817137D01*
G01X331776Y818674D02*
X332722Y817323D01*
G01X328603Y823205D02*
X329980Y821238D01*
G01X327303Y827675D02*
Y822795D01*
G01X328603Y827675D02*
Y823205D01*
G01X316004Y823635D02*
Y827675D01*
G01X314704Y823224D02*
Y827675D01*
G01X319799Y818216D02*
X316004Y823635D01*
G01X318865Y817283D02*
X314704Y823224D01*
G01X321337Y817137D02*
X319799Y818216D01*
G01X322367Y817318D02*
X321337Y817137D01*
G01X359424Y208475D02*
X369060Y202217D01*
G01X359930Y209697D02*
X370000Y203157D01*
G01X336137Y213424D02*
X359424Y208475D01*
G01X359930Y209697D02*
X370000Y203157D01*
G01X359424Y208475D02*
X369060Y202217D01*
G01X336137Y213424D02*
X359424Y208475D01*
G01X373108Y206912D02*
X360567Y215055D01*
G01X374048Y207852D02*
X361073Y216277D01*
G01X374048Y207852D02*
X361073Y216277D01*
G01X373108Y206912D02*
X360567Y215055D01*
G01X365500Y302634D02*
X388315Y297784D01*
G01X365637Y303934D02*
X388310Y299115D01*
G01X342752Y302634D02*
X365500D01*
G01X363987Y303934D02*
X365637D01*
G01X342752D02*
X360937D01*
G01X365637D02*
X388310Y299115D01*
G01X365500Y302634D02*
X388315Y297784D01*
G01X363987Y303934D02*
X365637D01*
G01X342752Y302634D02*
X365500D01*
G01X342752Y303934D02*
X360937D01*
G01X342752Y302634D02*
X365500D01*
G01X354421Y693743D02*
G03X353779I-321J-1822D01*
G01X354005Y692462D02*
G02X354195I95J-541D01*
G01X391353Y687231D02*
X354421Y693743D01*
G01X354195Y692462D02*
X391127Y685950D01*
G01X354195Y692462D02*
X391127Y685950D01*
G01X391353Y687231D02*
X354421Y693743D01*
G01X354005Y692462D02*
G02X354195I95J-541D01*
G01X354421Y693743D02*
G03X353779I-321J-1822D01*
G01X365545Y727342D02*
X363602Y729285D01*
G01X364523Y730204D02*
X366465Y728262D01*
G01X367339Y726600D02*
G02X365545Y727342I-1J2537D01*
G01X366465Y728262D02*
G03X367339Y727900I874J874D01*
G01X376200Y726600D02*
X367339D01*
G01Y727900D02*
X376200D01*
G01X367339D02*
X376200D01*
G01Y726600D02*
X367339D01*
G01X366465Y728262D02*
G03X367339Y727900I874J874D01*
G01Y726600D02*
G02X365545Y727342I-1J2537D01*
G01X364523Y730204D02*
X366465Y728262D01*
G01X365545Y727342D02*
X363602Y729285D01*
G01X649444Y578236D02*
X334490Y798769D01*
G01X650378Y579170D02*
X335000Y800000D01*
G01X650378Y579170D02*
X335000Y800000D01*
G01X649444Y578236D02*
X334490Y798769D01*
G01X647113Y576956D02*
X335000Y795500D01*
G01X646179Y576022D02*
X334490Y794269D01*
G01X646179Y576022D02*
X334490Y794269D01*
G01X647113Y576956D02*
X335000Y795500D01*
G01X639686Y572018D02*
X334700Y785571D01*
G01X638752Y571084D02*
X334190Y784340D01*
G01X638752Y571084D02*
X334190Y784340D01*
G01X639686Y572018D02*
X334700Y785571D01*
G01X347658Y807866D02*
X656566Y591566D01*
G01X348592Y808800D02*
X657500Y592500D01*
G01X339901Y818945D02*
X347658Y807866D01*
G01X341201Y819355D02*
X348592Y808800D01*
G01X361210Y803627D02*
X659066Y595066D01*
G01X362144Y804561D02*
X660000Y596000D01*
G01X352500Y816066D02*
X361210Y803627D01*
G01X353800Y816477D02*
X362144Y804561D01*
G01X352500Y827675D02*
Y816066D01*
G01X365098Y816279D02*
X368439Y812938D01*
G01X366398Y816818D02*
X369903Y813313D01*
G01X365098Y827200D02*
Y816279D01*
G01X348592Y808800D02*
X657500Y592500D01*
G01X347658Y807866D02*
X656566Y591566D01*
G01X341201Y819355D02*
X348592Y808800D01*
G01X339901Y818945D02*
X347658Y807866D01*
G01X362144Y804561D02*
X660000Y596000D01*
G01X361210Y803627D02*
X659066Y595066D01*
G01X353800Y816477D02*
X362144Y804561D01*
G01X352500Y816066D02*
X361210Y803627D01*
G01X352500Y827675D02*
Y816066D01*
G01X366398Y816818D02*
X369903Y813313D01*
G01X365098Y816279D02*
X368439Y812938D01*
G01X365098Y827200D02*
Y816279D01*
G01X337500Y810500D02*
X653814Y589015D01*
G01X336566Y809566D02*
X652880Y588081D01*
G01X334518Y814759D02*
X337500Y810500D01*
G01X648205Y586652D02*
X333989Y806670D01*
G01X648951Y587717D02*
X334735Y807735D01*
G01X336566Y809566D02*
X652880Y588081D01*
G01X337500Y810500D02*
X653814Y589015D01*
G01X334518Y814759D02*
X337500Y810500D01*
G01X648951Y587717D02*
X334735Y807735D01*
G01X648205Y586652D02*
X333989Y806670D01*
G01X339901Y827675D02*
Y818945D01*
G01X341201Y827675D02*
Y819355D01*
G01X353800Y827675D02*
Y816477D01*
G01X366398Y827200D02*
Y816818D01*
G01X341201Y827675D02*
Y819355D01*
G01X339901Y827675D02*
Y818945D01*
G01X353800Y827675D02*
Y816477D01*
G01X366398Y827200D02*
Y816818D01*
G01X388652Y174154D02*
X385865Y187268D01*
G01X389982Y174154D02*
X387087Y187774D01*
G01X387243Y167526D02*
X388652Y174154D01*
G01X388573Y167526D02*
X389982Y174154D01*
G01X389170Y158464D02*
X387243Y167526D01*
G01X390392Y158970D02*
X388573Y167526D01*
G01X390410Y156554D02*
X389170Y158464D01*
G01X391350Y157495D02*
X390392Y158970D01*
G01X393127Y154791D02*
X390410Y156554D01*
G01X393633Y156013D02*
X391350Y157495D01*
G01X395367Y154315D02*
X393127Y154791D01*
G01X395504Y155615D02*
X393633Y156013D01*
G01X400200Y154315D02*
X395367D01*
G01X400200Y155615D02*
X395504D01*
G01X389982Y174154D02*
X387087Y187774D01*
G01X388652Y174154D02*
X385865Y187268D01*
G01X388573Y167526D02*
X389982Y174154D01*
G01X387243Y167526D02*
X388652Y174154D01*
G01X390392Y158970D02*
X388573Y167526D01*
G01X389170Y158464D02*
X387243Y167526D01*
G01X391350Y157495D02*
X390392Y158970D01*
G01X390410Y156554D02*
X389170Y158464D01*
G01X393633Y156013D02*
X391350Y157495D01*
G01X393127Y154791D02*
X390410Y156554D01*
G01X395504Y155615D02*
X393633Y156013D01*
G01X395367Y154315D02*
X393127Y154791D01*
G01X400200Y155615D02*
X395504D01*
G01X400200Y154315D02*
X395367D01*
G01X397117Y143642D02*
X402500D01*
G01X397502Y144942D02*
X402500D01*
G01X385823Y150972D02*
X397117Y143642D01*
G01X386763Y151912D02*
X397502Y144942D01*
G01X383374Y154744D02*
X385823Y150972D01*
G01X384596Y155250D02*
X386763Y151912D01*
G01X380642Y167593D02*
X383374Y154744D01*
G01X381972Y167593D02*
X384596Y155250D01*
G01X382135Y174614D02*
X380642Y167593D01*
G01X383465Y174614D02*
X381972Y167593D01*
G01X379776Y185718D02*
X382135Y174614D01*
G01X380998Y186224D02*
X383465Y174614D01*
G01X397502Y144942D02*
X402500D01*
G01X397117Y143642D02*
X402500D01*
G01X386763Y151912D02*
X397502Y144942D01*
G01X385823Y150972D02*
X397117Y143642D01*
G01X384596Y155250D02*
X386763Y151912D01*
G01X383374Y154744D02*
X385823Y150972D01*
G01X381972Y167593D02*
X384596Y155250D01*
G01X380642Y167593D02*
X383374Y154744D01*
G01X383465Y174614D02*
X381972Y167593D01*
G01X382135Y174614D02*
X380642Y167593D01*
G01X380998Y186224D02*
X383465Y174614D01*
G01X379776Y185718D02*
X382135Y174614D01*
G01X385865Y187268D02*
X373108Y206912D01*
G01X387087Y187774D02*
X374048Y207852D01*
G01X387087Y187774D02*
X374048Y207852D01*
G01X385865Y187268D02*
X373108Y206912D01*
G01X369060Y202217D02*
X379776Y185718D01*
G01X370000Y203157D02*
X380998Y186224D01*
G01X370000Y203157D02*
X380998Y186224D01*
G01X369060Y202217D02*
X379776Y185718D01*
G01X388310Y299115D02*
X436851Y309800D01*
G01X388315Y297784D02*
X412585Y303127D01*
G01X388310Y299115D02*
X436851Y309800D01*
G01X388310Y299115D02*
X436851Y309800D01*
G01X388315Y297784D02*
X412585Y303127D01*
G01X466533Y634801D02*
X392093Y686925D01*
G01X391347Y685859D02*
X465787Y633736D01*
G01X391347Y685859D02*
X465787Y633736D01*
G01X466533Y634801D02*
X392093Y686925D01*
G01X621731Y556999D02*
X381865Y724955D01*
G01X383404Y725465D02*
X622665Y557933D01*
G01X383404Y725465D02*
X622665Y557933D01*
G01X621731Y556999D02*
X381865Y724955D01*
G01X392093Y686925D02*
G03X391353Y687231I-1060J-1516D01*
G01X391127Y685950D02*
G02X391347Y685859I-95J-541D01*
G01X391127Y685950D02*
G02X391347Y685859I-95J-541D01*
G01X392093Y686925D02*
G03X391353Y687231I-1060J-1516D01*
G01X381865Y724955D02*
G03X376200Y726600I-5665J-8932D01*
G01Y727900D02*
G02X383404Y725465I0J-11874D01*
G01X376200Y727900D02*
G02X383404Y725465I0J-11874D01*
G01X381865Y724955D02*
G03X376200Y726600I-5665J-8932D01*
G01X393594Y808529D02*
X669452Y615374D01*
G01X394528Y809463D02*
X670386Y616308D01*
G01X387146Y817738D02*
X393594Y808529D01*
G01X388446Y818149D02*
X394528Y809463D01*
G01D02*
X670386Y616308D01*
G01X393594Y808529D02*
X669452Y615374D01*
G01X388446Y818149D02*
X394528Y809463D01*
G01X387146Y817738D02*
X393594Y808529D01*
G01X391037Y801981D02*
X666976Y608769D01*
G01X391547Y803212D02*
X667910Y609703D01*
G01X376902Y804473D02*
X391037Y801981D01*
G01X377532Y805683D02*
X391547Y803212D01*
G01X368439Y812938D02*
X376902Y804473D01*
G01X369903Y813313D02*
X377532Y805683D01*
G01X391547Y803212D02*
X667910Y609703D01*
G01X391037Y801981D02*
X666976Y608769D01*
G01X377532Y805683D02*
X391547Y803212D01*
G01X376902Y804473D02*
X391037Y801981D01*
G01X369903Y813313D02*
X377532Y805683D01*
G01X368439Y812938D02*
X376902Y804473D01*
G01X399744Y822488D02*
X415210Y800399D01*
G01X401044Y822898D02*
X416144Y801333D01*
G01X399744Y827675D02*
Y822488D01*
G01X401044Y827675D02*
Y822898D01*
G01D02*
X416144Y801333D01*
G01X399744Y822488D02*
X415210Y800399D01*
G01X401044Y827675D02*
Y822898D01*
G01X399744Y827675D02*
Y822488D01*
G01X387146Y827675D02*
Y817738D01*
G01X388446Y827675D02*
Y818149D01*
G01Y827675D02*
Y818149D01*
G01X387146Y827675D02*
Y817738D01*
G01X412585Y303127D02*
X436855Y308469D01*
G01X412585Y303127D02*
X436855Y308469D01*
G01X427019Y798377D02*
X413210Y818099D01*
G01X414441Y818609D02*
X427953Y799311D01*
G01X676759Y623509D02*
X427019Y798377D01*
G01X427953Y799311D02*
X677693Y624443D01*
G01X432445Y802741D02*
X678594Y630392D01*
G01X679528Y631326D02*
X433379Y803675D01*
G01X427431Y809901D02*
X432445Y802741D01*
G01X433379Y803675D02*
X428662Y810411D01*
G01X424941Y824023D02*
X427431Y809901D01*
G01X428662Y810411D02*
X426241Y824139D01*
G01X427953Y799311D02*
X677693Y624443D01*
G01X676759Y623509D02*
X427019Y798377D01*
G01X414441Y818609D02*
X427953Y799311D01*
G01X427019Y798377D02*
X413210Y818099D01*
G01X428662Y810411D02*
X426241Y824139D01*
G01X424941Y824023D02*
X427431Y809901D01*
G01X433379Y803675D02*
X428662Y810411D01*
G01X427431Y809901D02*
X432445Y802741D01*
G01X679528Y631326D02*
X433379Y803675D01*
G01X432445Y802741D02*
X678594Y630392D01*
G01X415210Y800399D02*
X672103Y620518D01*
G01X416144Y801333D02*
X673037Y621452D01*
G01X416144Y801333D02*
X673037Y621452D01*
G01X415210Y800399D02*
X672103Y620518D01*
G01X412343Y823018D02*
Y827675D01*
G01X413643D02*
Y823135D01*
G01X413210Y818099D02*
X412343Y823018D01*
G01X413643Y823135D02*
X414441Y818609D01*
G01X424941Y827675D02*
Y824023D01*
G01X426241Y824139D02*
Y827675D01*
G01X413643Y823135D02*
X414441Y818609D01*
G01X413210Y818099D02*
X412343Y823018D01*
G01X413643Y827675D02*
Y823135D01*
G01X412343Y823018D02*
Y827675D01*
G01X426241Y824139D02*
Y827675D01*
G01X424941D02*
Y824023D01*
G01X436855Y308469D02*
X478781Y299507D01*
G01X436851Y309800D02*
X478782Y300837D01*
G01X436851Y309800D02*
X478782Y300837D01*
G01X436855Y308469D02*
X478781Y299507D01*
G01X466987Y634347D02*
G03X466533Y634801I-1515J-1061D01*
G01X465787Y633736D02*
G02X465922Y633601I-315J-450D01*
G01X499944Y587279D02*
X466987Y634347D01*
G01X465922Y633601D02*
X498879Y586533D01*
G01X465922Y633601D02*
X498879Y586533D01*
G01X499944Y587279D02*
X466987Y634347D01*
G01X465787Y633736D02*
G02X465922Y633601I-315J-450D01*
G01X466987Y634347D02*
G03X466533Y634801I-1515J-1061D01*
G01X478782Y300837D02*
X537686Y313369D01*
G01X478782Y300837D02*
X537686Y313369D01*
G01X478781Y299507D02*
X537962Y312098D01*
G01X478782Y300837D02*
X537686Y313369D01*
G01X478782Y300837D02*
X537686Y313369D01*
G01X478781Y299507D02*
X537962Y312098D01*
G01X500079Y587144D02*
G02X499944Y587279I316J451D01*
G01X498879Y586533D02*
G03X499333Y586079I1516J1062D01*
G01X574350Y535140D02*
X500079Y587144D01*
G01X499333Y586079D02*
X573604Y534075D01*
G01X499333Y586079D02*
X573604Y534075D01*
G01X574350Y535140D02*
X500079Y587144D01*
G01X498879Y586533D02*
G03X499333Y586079I1516J1062D01*
G01X500079Y587144D02*
G02X499944Y587279I316J451D01*
G01X527927Y141523D02*
Y142694D01*
G01X529227D02*
Y141523D01*
G01X517050Y141437D02*
G02X517813Y143283I2609J2D01*
G01X518733Y142363D02*
G03X518350Y141438I925J-925D01*
G01X517050Y139686D02*
Y141437D01*
G01X518350Y141438D02*
Y139686D01*
G01X529227Y142694D02*
Y141523D01*
G01X527927D02*
Y142694D01*
G01X518350Y141438D02*
Y139686D01*
G01X517050D02*
Y141437D01*
G01X518733Y142363D02*
G03X518350Y141438I925J-925D01*
G01X517050Y141437D02*
G02X517813Y143283I2609J2D01*
G01X530083Y144850D02*
X544919D01*
G01X531733Y143550D02*
X530083D01*
G01X536433D02*
X534783D01*
G01X527927Y142694D02*
G02X530083Y144850I2156J0D01*
G01Y143550D02*
G03X529227Y142694I0J-856D01*
G01X524639Y148200D02*
X541766D01*
G01X541904Y146900D02*
X524639D01*
G01X521382Y146851D02*
G02X524639Y148200I3257J-3257D01*
G01Y146900D02*
G03X522302Y145931I1J-3306D01*
G01X517813Y143283D02*
X521382Y146851D01*
G01X522302Y145931D02*
X518733Y142363D01*
G01X530083Y143550D02*
G03X529227Y142694I0J-856D01*
G01X527927D02*
G02X530083Y144850I2156J0D01*
G01X531733Y143550D02*
X530083D01*
G01Y144850D02*
X544919D01*
G01X536433Y143550D02*
X534783D01*
G01X530083Y144850D02*
X544919D01*
G01X530083D02*
X544919D01*
G01X522302Y145931D02*
X518733Y142363D01*
G01X517813Y143283D02*
X521382Y146851D01*
G01X524639Y146900D02*
G03X522302Y145931I1J-3306D01*
G01X521382Y146851D02*
G02X524639Y148200I3257J-3257D01*
G01X541904Y146900D02*
X524639D01*
G01Y148200D02*
X541766D01*
G01X549037Y141087D02*
X550561Y142077D01*
G01X546748Y140410D02*
G03X549037Y141087I1J4204D01*
G01X544505Y140410D02*
X546748D01*
G01X542550Y139755D02*
G02X544505Y141710I1955J0D01*
G01X543850Y139755D02*
G02X544505Y140410I655J0D01*
G01X542550Y138584D02*
Y139755D01*
G01X543850Y138584D02*
Y139755D01*
G01X549037Y141087D02*
X550561Y142077D01*
G01X546748Y140410D02*
G03X549037Y141087I1J4204D01*
G01X544505Y140410D02*
X546748D01*
G01X543850Y139755D02*
G02X544505Y140410I655J0D01*
G01X542550Y139755D02*
G02X544505Y141710I1955J0D01*
G01X543850Y138584D02*
Y139755D01*
G01X542550Y138584D02*
Y139755D01*
G01X558711Y161076D02*
X572418Y169971D01*
G01X561659Y161439D02*
X559241Y159870D01*
G01X565602Y163997D02*
X564218Y163099D01*
G01X572924Y168749D02*
X568161Y165658D01*
G01X548786Y158486D02*
X558708Y161076D01*
G01X554693Y158683D02*
X549456Y157317D01*
G01X559241Y159870D02*
X557644Y159453D01*
G01X547429Y157130D02*
X548786Y158486D01*
G01X549456Y157317D02*
X548349Y156210D01*
G01X546500Y154885D02*
G02X547429Y157130I3174J1D01*
G01X548349Y156210D02*
G03X547800Y154885I1324J-1325D01*
G01X546500Y153200D02*
Y154885D01*
G01X547800D02*
Y153100D01*
G01Y154885D02*
Y153100D01*
G01X546500Y153200D02*
Y154885D01*
G01X548349Y156210D02*
G03X547800Y154885I1324J-1325D01*
G01X546500D02*
G02X547429Y157130I3174J1D01*
G01X549456Y157317D02*
X548349Y156210D01*
G01X547429Y157130D02*
X548786Y158486D01*
G01X554693Y158683D02*
X549456Y157317D01*
G01X548786Y158486D02*
X558708Y161076D01*
G01X559241Y159870D02*
X557644Y159453D01*
G01X548786Y158486D02*
X558708Y161076D01*
G01X561659Y161439D02*
X559241Y159870D01*
G01X558711Y161076D02*
X572418Y169971D01*
G01X565602Y163997D02*
X564218Y163099D01*
G01X558711Y161076D02*
X572418Y169971D01*
G01X572924Y168749D02*
X568161Y165658D01*
G01X558711Y161076D02*
X572418Y169971D01*
G01X563541Y146386D02*
X580048Y158235D01*
G01X564078Y145171D02*
X572508Y151221D01*
G01X551382Y143800D02*
X563541Y146386D01*
G01X551652Y142528D02*
X564078Y145171D01*
G01X550211Y143377D02*
G02X551382Y143800I2113J-4017D01*
G01X550816Y142226D02*
G02X551652Y142528I1508J-2866D01*
G01X550562Y142077D02*
G02X550813Y142223I1752J-2723D01*
G01X548329Y142178D02*
X550175Y143377D01*
G01X550561Y142077D02*
X550562D01*
G01X546749Y141710D02*
G03X548329Y142178I-1J2903D01*
G01X544505Y141710D02*
X546749D01*
G01X563541Y146386D02*
X580048Y158235D01*
G01X563541Y146386D02*
X580048Y158235D01*
G01X563541Y146386D02*
X580048Y158235D01*
G01X563541Y146386D02*
X580048Y158235D01*
G01X564078Y145171D02*
X572508Y151221D01*
G01X563541Y146386D02*
X580048Y158235D01*
G01X551652Y142528D02*
X564078Y145171D01*
G01X551382Y143800D02*
X563541Y146386D01*
G01X550816Y142226D02*
G02X551652Y142528I1508J-2866D01*
G01X550211Y143377D02*
G02X551382Y143800I2113J-4017D01*
G01X550562Y142077D02*
G02X550813Y142223I1752J-2723D01*
G01X550211Y143377D02*
G02X551382Y143800I2113J-4017D01*
G01X550561Y142077D02*
X550562D01*
G01X548329Y142178D02*
X550175Y143377D01*
G01X548329Y142178D02*
X550175Y143377D01*
G01X546749Y141710D02*
G03X548329Y142178I-1J2903D01*
G01X544505Y141710D02*
X546749D01*
G01X556895Y148196D02*
X582425Y164776D01*
G01X582931Y163554D02*
X557401Y146974D01*
G01X547632Y146229D02*
X556895Y148196D01*
G01X557401Y146974D02*
X547902Y144957D01*
G01X545655Y145156D02*
G02X547632Y146229I2799J-2799D01*
G01X547902Y144957D02*
G03X546575Y144236I553J-2600D01*
G01X544919Y144850D02*
G03X545655Y145156I-1J1041D01*
G01X546575Y144236D02*
G02X544919Y143550I-1656J1656D01*
G01D02*
X539483D01*
G01X551744Y150320D02*
X579000Y168018D01*
G01X557137Y152271D02*
X552250Y149098D01*
G01X561079Y154831D02*
X559695Y153932D01*
G01X579506Y166796D02*
X563637Y156492D01*
G01X541767Y148201D02*
X551744Y150320D01*
G01X552250Y149098D02*
X541904Y146900D01*
G01X544919Y143550D02*
X539483D01*
G01X546575Y144236D02*
G02X544919Y143550I-1656J1656D01*
G01Y144850D02*
G03X545655Y145156I-1J1041D01*
G01X547902Y144957D02*
G03X546575Y144236I553J-2600D01*
G01X545655Y145156D02*
G02X547632Y146229I2799J-2799D01*
G01X557401Y146974D02*
X547902Y144957D01*
G01X547632Y146229D02*
X556895Y148196D01*
G01X582931Y163554D02*
X557401Y146974D01*
G01X556895Y148196D02*
X582425Y164776D01*
G01X552250Y149098D02*
X541904Y146900D01*
G01X541767Y148201D02*
X551744Y150320D01*
G01X557137Y152271D02*
X552250Y149098D01*
G01X551744Y150320D02*
X579000Y168018D01*
G01X561079Y154831D02*
X559695Y153932D01*
G01X551744Y150320D02*
X579000Y168018D01*
G01X579506Y166796D02*
X563637Y156492D01*
G01X551744Y150320D02*
X579000Y168018D01*
G01X567686Y320974D02*
G03X570438Y319835I2751J2754D01*
G01X568606Y321894D02*
G03X570438Y321135I1833J1833D01*
G01X566161Y322499D02*
X567686Y320974D01*
G01X567081Y323418D02*
X568606Y321894D01*
G01X565437Y322800D02*
G02X566161Y322499I-1J-1024D01*
G01X565438Y324100D02*
G02X567081Y323418I-2J-2324D01*
G01X554937Y322800D02*
X565437D01*
G01X554800Y324100D02*
X565438D01*
G01X552035Y322182D02*
X554937Y322800D01*
G01X551529Y323404D02*
X554800Y324100D01*
G01X548500Y319887D02*
X552035Y322182D01*
G01X547560Y320827D02*
X551529Y323404D01*
G01X545886Y315862D02*
X548500Y319887D01*
G01X544796Y316571D02*
X547560Y320827D01*
G01X545736Y315631D02*
X545886Y315861D01*
G01X544796Y316571D02*
X547560Y320827D01*
G01X541430Y312835D02*
X545736Y315631D01*
G01X540924Y314057D02*
X544796Y316571D01*
G01X538290Y312168D02*
X541430Y312835D01*
G01X539473Y313750D02*
X540924Y314057D01*
G01X537686Y313369D02*
X539473Y313749D01*
G01X538119Y312131D02*
X538290Y312168D01*
G01X537686Y313369D02*
X539473Y313749D01*
G01X537985Y312103D02*
X538119Y312131D01*
G01X537686Y313369D02*
X539473Y313749D01*
G01X537962Y312098D02*
X537985Y312103D01*
G01X537686Y313369D02*
X539473Y313749D01*
G01X568606Y321894D02*
G03X570438Y321135I1833J1833D01*
G01X567686Y320974D02*
G03X570438Y319835I2751J2754D01*
G01X567081Y323418D02*
X568606Y321894D01*
G01X566161Y322499D02*
X567686Y320974D01*
G01X565438Y324100D02*
G02X567081Y323418I-2J-2324D01*
G01X565437Y322800D02*
G02X566161Y322499I-1J-1024D01*
G01X554800Y324100D02*
X565438D01*
G01X554937Y322800D02*
X565437D01*
G01X551529Y323404D02*
X554800Y324100D01*
G01X552035Y322182D02*
X554937Y322800D01*
G01X547560Y320827D02*
X551529Y323404D01*
G01X548500Y319887D02*
X552035Y322182D01*
G01X544796Y316571D02*
X547560Y320827D01*
G01X545886Y315862D02*
X548500Y319887D01*
G01X545736Y315631D02*
X545886Y315861D01*
G01X540924Y314057D02*
X544796Y316571D01*
G01X541430Y312835D02*
X545736Y315631D01*
G01X539473Y313750D02*
X540924Y314057D01*
G01X538290Y312168D02*
X541430Y312835D01*
G01X537686Y313369D02*
X539473Y313749D01*
G01X538290Y312168D02*
X541430Y312835D01*
G01X538119Y312131D02*
X538290Y312168D01*
G01X537985Y312103D02*
X538119Y312131D01*
G01X537962Y312098D02*
X537985Y312103D01*
G01D02*
X538119Y312131D01*
G01X537962Y312098D02*
X537985Y312103D01*
G01X574066Y737566D02*
X546201Y777362D01*
G01X547501Y777772D02*
X575000Y738500D01*
G01X547501Y777772D02*
X575000Y738500D01*
G01X574066Y737566D02*
X546201Y777362D01*
G01X558800Y771010D02*
X579066Y742066D01*
G01X560100Y771420D02*
X580000Y743000D01*
G01X558800Y828200D02*
Y771010D01*
G01X560100Y828200D02*
Y771420D01*
G01D02*
X580000Y743000D01*
G01X558800Y771010D02*
X579066Y742066D01*
G01X560100Y828200D02*
Y771420D01*
G01X558800Y828200D02*
Y771010D01*
G01X546201Y777362D02*
Y828007D01*
G01X547501D02*
Y777772D01*
G01Y828007D02*
Y777772D01*
G01X546201Y777362D02*
Y828007D01*
G01X602200Y139982D02*
X602814Y142410D01*
G01X603956Y141622D02*
X603500Y139820D01*
G01X602200Y139335D02*
Y139982D01*
G01X603500Y139820D02*
Y139335D01*
G01X587465Y141765D02*
X587885Y142185D01*
G01X585700Y140643D02*
G02X586545Y142685I2887J1D01*
G01X587000Y140643D02*
G02X587465Y141765I1586J0D01*
G01X585700Y139700D02*
Y140643D01*
G01X587000Y139700D02*
Y140643D01*
G01X575400Y139903D02*
G02X576587Y142770I4056J0D01*
G01X576700Y139902D02*
G02X577507Y141850I2755J0D01*
G01X575400Y139321D02*
Y139903D01*
G01X576700Y139321D02*
Y139902D01*
G01X603500Y139820D02*
Y139335D01*
G01X602200D02*
Y139982D01*
G01X603956Y141622D02*
X603500Y139820D01*
G01X602200Y139982D02*
X602814Y142410D01*
G01X587465Y141765D02*
X587885Y142185D01*
G01X587000Y140643D02*
G02X587465Y141765I1586J0D01*
G01X585700Y140643D02*
G02X586545Y142685I2887J1D01*
G01X587000Y139700D02*
Y140643D01*
G01X585700Y139700D02*
Y140643D01*
G01X576700Y139902D02*
G02X577507Y141850I2755J0D01*
G01X575400Y139903D02*
G02X576587Y142770I4056J0D01*
G01X576700Y139321D02*
Y139902D01*
G01X575400Y139321D02*
Y139903D01*
G01X598746Y158280D02*
X614108Y161551D01*
G01X599276Y157063D02*
X614641Y160335D01*
G01X595753Y156183D02*
X598746Y158280D01*
G01X596816Y155339D02*
X599276Y157063D01*
G01X595100Y154556D02*
X595753Y156183D01*
G01X596400Y154304D02*
X596816Y155339D01*
G01X595100Y151576D02*
Y154556D01*
G01X596400Y151576D02*
Y154304D01*
G01X599276Y157063D02*
X614641Y160335D01*
G01X598746Y158280D02*
X614108Y161551D01*
G01X596816Y155339D02*
X599276Y157063D01*
G01X595753Y156183D02*
X598746Y158280D01*
G01X596400Y154304D02*
X596816Y155339D01*
G01X595100Y154556D02*
X595753Y156183D01*
G01X596400Y151576D02*
Y154304D01*
G01X595100Y151576D02*
Y154556D01*
G01X602814Y142410D02*
X606557Y145029D01*
G01X599859Y144747D02*
X609056Y150714D01*
G01X600365Y143525D02*
X609562Y149492D01*
G01X593336Y143361D02*
X599859Y144747D01*
G01X598751Y143182D02*
X600365Y143525D01*
G01X593607Y142089D02*
X595768Y142548D01*
G01X592847Y143360D02*
G03X593336Y143361I242J1156D01*
G01X592578Y142088D02*
G03X593607Y142089I512J2428D01*
G01X591329Y143682D02*
X592847Y143360D01*
G01X591059Y142410D02*
X592578Y142088D01*
G01X589768Y143846D02*
G02X591329Y143682I-2J-7528D01*
G01X589767Y142546D02*
G02X591059Y142410I-2J-6228D01*
G01X588756Y143846D02*
X589768D01*
G01X588756Y142546D02*
X589767D01*
G01X586965Y143105D02*
G02X588756Y143846I1790J-1791D01*
G01X587885Y142185D02*
G02X588756Y142546I871J-870D01*
G01X586545Y142685D02*
X586965Y143105D01*
G01X598661Y147720D02*
X606146Y153438D01*
G01X599218Y146508D02*
X606707Y152230D01*
G01X594781Y146896D02*
X598661Y147720D01*
G01X594781Y145566D02*
X599218Y146508D01*
G01X589003Y148125D02*
X594781Y146896D01*
G01X589003Y146795D02*
X594781Y145566D01*
G01X585706Y147424D02*
X589003Y148125D01*
G01X585976Y146152D02*
X589003Y146795D01*
G01X582031Y146643D02*
X585706Y147424D01*
G01X582537Y145421D02*
X585976Y146152D01*
G01X577554Y143736D02*
X582031Y146643D01*
G01X578377Y142720D02*
X582537Y145421D01*
G01X576587Y142770D02*
X577554Y143736D01*
G01X577507Y141850D02*
X578377Y142720D01*
G01X602814Y142410D02*
X606557Y145029D01*
G01X600365Y143525D02*
X609562Y149492D01*
G01X599859Y144747D02*
X609056Y150714D01*
G01X598751Y143182D02*
X600365Y143525D01*
G01X593336Y143361D02*
X599859Y144747D01*
G01X593607Y142089D02*
X595768Y142548D01*
G01X593336Y143361D02*
X599859Y144747D01*
G01X592578Y142088D02*
G03X593607Y142089I512J2428D01*
G01X592847Y143360D02*
G03X593336Y143361I242J1156D01*
G01X591059Y142410D02*
X592578Y142088D01*
G01X591329Y143682D02*
X592847Y143360D01*
G01X589767Y142546D02*
G02X591059Y142410I-2J-6228D01*
G01X589768Y143846D02*
G02X591329Y143682I-2J-7528D01*
G01X588756Y142546D02*
X589767D01*
G01X588756Y143846D02*
X589768D01*
G01X587885Y142185D02*
G02X588756Y142546I871J-870D01*
G01X586965Y143105D02*
G02X588756Y143846I1790J-1791D01*
G01X586545Y142685D02*
X586965Y143105D01*
G01X599218Y146508D02*
X606707Y152230D01*
G01X598661Y147720D02*
X606146Y153438D01*
G01X594781Y145566D02*
X599218Y146508D01*
G01X594781Y146896D02*
X598661Y147720D01*
G01X589003Y146795D02*
X594781Y145566D01*
G01X589003Y148125D02*
X594781Y146896D01*
G01X585976Y146152D02*
X589003Y146795D01*
G01X585706Y147424D02*
X589003Y148125D01*
G01X582537Y145421D02*
X585976Y146152D01*
G01X582031Y146643D02*
X585706Y147424D01*
G01X578377Y142720D02*
X582537Y145421D01*
G01X577554Y143736D02*
X582031Y146643D01*
G01X577507Y141850D02*
X578377Y142720D01*
G01X576587Y142770D02*
X577554Y143736D01*
G01X572418Y169971D02*
X644201Y185231D01*
G01Y183901D02*
X572924Y168749D01*
G01X644201Y183901D02*
X572924Y168749D01*
G01X572418Y169971D02*
X644201Y185231D01*
G01X580056Y158237D02*
X612530Y165153D01*
G01X580585Y157020D02*
X613063Y163937D01*
G01X578803Y155741D02*
X580585Y157020D01*
G01X576326Y153962D02*
X577303Y153802D01*
G01X574985Y153000D02*
X576326Y153962D01*
G01X572508Y151221D02*
X573485Y151061D01*
G01X580585Y157020D02*
X613063Y163937D01*
G01X580056Y158237D02*
X612530Y165153D01*
G01X578803Y155741D02*
X580585Y157020D01*
G01X576326Y153962D02*
X577303Y153802D01*
G01X574985Y153000D02*
X576326Y153962D01*
G01X572508Y151221D02*
X573485Y151061D01*
G01X582425Y164776D02*
X644947Y178077D01*
G01X584545Y163897D02*
X582931Y163554D01*
G01X589142Y164875D02*
X587528Y164532D01*
G01X593739Y165853D02*
X592125Y165510D01*
G01X598336Y166831D02*
X596722Y166488D01*
G01X644947Y176747D02*
X601319Y167466D01*
G01X579000Y168018D02*
X643520Y181732D01*
G01Y180402D02*
X579506Y166796D01*
G01X584545Y163897D02*
X582931Y163554D01*
G01X582425Y164776D02*
X644947Y178077D01*
G01X589142Y164875D02*
X587528Y164532D01*
G01X582425Y164776D02*
X644947Y178077D01*
G01X593739Y165853D02*
X592125Y165510D01*
G01X582425Y164776D02*
X644947Y178077D01*
G01X598336Y166831D02*
X596722Y166488D01*
G01X582425Y164776D02*
X644947Y178077D01*
G01Y176747D02*
X601319Y167466D01*
G01X582425Y164776D02*
X644947Y178077D01*
G01X643520Y180402D02*
X579506Y166796D01*
G01X579000Y168018D02*
X643520Y181732D01*
G01X570438Y319835D02*
X628017D01*
G01X601618Y321135D02*
X628018D01*
G01X596918D02*
X598568D01*
G01X592218D02*
X593868D01*
G01X570438D02*
X589168D01*
G01X601618D02*
X628018D01*
G01X570438Y319835D02*
X628017D01*
G01X596918Y321135D02*
X598568D01*
G01X570438Y319835D02*
X628017D01*
G01X592218Y321135D02*
X593868D01*
G01X570438Y319835D02*
X628017D01*
G01X570438Y321135D02*
X589168D01*
G01X570438Y319835D02*
X628017D01*
G01X613727Y479098D02*
X574804Y534686D01*
G01X573739Y533940D02*
X612662Y478352D01*
G01X573739Y533940D02*
X612662Y478352D01*
G01X613727Y479098D02*
X574804Y534686D01*
G01D02*
G03X574350Y535140I-1515J-1061D01*
G01X573604Y534075D02*
G02X573739Y533940I-315J-450D01*
G01X573604Y534075D02*
G02X573739Y533940I-315J-450D01*
G01X574804Y534686D02*
G03X574350Y535140I-1515J-1061D01*
G01X584066Y747566D02*
X650652Y700942D01*
G01X585000Y748500D02*
X651586Y701876D01*
G01X571398Y765658D02*
X584066Y747566D01*
G01X572698Y766068D02*
X585000Y748500D01*
G01X594066Y749066D02*
X651152Y709094D01*
G01X595000Y750000D02*
X652086Y710028D01*
G01X585000Y748500D02*
X651586Y701876D01*
G01X584066Y747566D02*
X650652Y700942D01*
G01X572698Y766068D02*
X585000Y748500D01*
G01X571398Y765658D02*
X584066Y747566D01*
G01X595000Y750000D02*
X652086Y710028D01*
G01X594066Y749066D02*
X651152Y709094D01*
G01X579066Y742066D02*
X648496Y693450D01*
G01X580000Y743000D02*
X649430Y694384D01*
G01X580000Y743000D02*
X649430Y694384D01*
G01X579066Y742066D02*
X648496Y693450D01*
G01X647149Y686392D02*
X574066Y737566D01*
G01X575000Y738500D02*
X648083Y687326D01*
G01X575000Y738500D02*
X648083Y687326D01*
G01X647149Y686392D02*
X574066Y737566D01*
G01X571398Y828300D02*
Y765658D01*
G01X572698Y828300D02*
Y766068D01*
G01X584000Y763444D02*
X594066Y749066D01*
G01X585300Y763854D02*
X595000Y750000D01*
G01X584000Y828003D02*
Y763444D01*
G01X585300Y828003D02*
Y763854D01*
G01X572698Y828300D02*
Y766068D01*
G01X571398Y828300D02*
Y765658D01*
G01X585300Y763854D02*
X595000Y750000D01*
G01X584000Y763444D02*
X594066Y749066D01*
G01X585300Y828003D02*
Y763854D01*
G01X584000Y828003D02*
Y763444D01*
G01X596595Y809302D02*
Y828007D01*
G01X597895Y809712D02*
Y828007D01*
G01X621097Y774308D02*
X596595Y809302D01*
G01X622162Y775054D02*
X597895Y809712D01*
G01D02*
Y828007D01*
G01X596595Y809302D02*
Y828007D01*
G01X622162Y775054D02*
X597895Y809712D01*
G01X621097Y774308D02*
X596595Y809302D01*
G01X635900Y139871D02*
Y139321D01*
G01X637200Y139871D02*
Y139321D01*
G01X638975Y142946D02*
G03X635900Y139871I0J-3075D01*
G01X638975Y141646D02*
G03X637200Y139871I0J-1775D01*
G01X625576Y141036D02*
G02X626663Y143663I3715J1D01*
G01X626876Y141036D02*
G02X627583Y142743I2414J0D01*
G01X625576Y139321D02*
Y141036D01*
G01X626876Y139321D02*
Y141036D01*
G01X637200Y139871D02*
Y139321D01*
G01X635900Y139871D02*
Y139321D01*
G01X638975Y141646D02*
G03X637200Y139871I0J-1775D01*
G01X638975Y142946D02*
G03X635900Y139871I0J-3075D01*
G01X626876Y141036D02*
G02X627583Y142743I2414J0D01*
G01X625576Y141036D02*
G02X626663Y143663I3715J1D01*
G01X626876Y139321D02*
Y141036D01*
G01X625576Y139321D02*
Y141036D01*
G01X607067Y143798D02*
X603956Y141622D01*
G01X607067Y143798D02*
X603956Y141622D01*
G01X630754Y146800D02*
X655593D01*
G01X630754Y145500D02*
X655475D01*
G01X629127Y146127D02*
G02X630754Y146800I1626J-1627D01*
G01X630047Y145207D02*
G02X630754Y145500I707J-706D01*
G01X626663Y143663D02*
X629127Y146127D01*
G01X627583Y142743D02*
X630047Y145207D01*
G01X630754Y145500D02*
X655475D01*
G01X630754Y146800D02*
X655593D01*
G01X630047Y145207D02*
G02X630754Y145500I707J-706D01*
G01X629127Y146127D02*
G02X630754Y146800I1626J-1627D01*
G01X627583Y142743D02*
X630047Y145207D01*
G01X626663Y143663D02*
X629127Y146127D01*
G01X618830Y164901D02*
X644013Y170263D01*
G01X619363Y163685D02*
X644013Y168933D01*
G01X614108Y161551D02*
X618830Y164901D01*
G01X614641Y160335D02*
X619363Y163685D01*
G01D02*
X644013Y168933D01*
G01X618830Y164901D02*
X644013Y170263D01*
G01X614641Y160335D02*
X619363Y163685D01*
G01X614108Y161551D02*
X618830Y164901D01*
G01X623776Y150185D02*
X637864Y159334D01*
G01X638370Y158112D02*
X624282Y148963D01*
G01X614353Y148182D02*
X623776Y150185D01*
G01X624282Y148963D02*
X615000Y146990D01*
G01X612193Y146022D02*
X614353Y148182D01*
G01X615000Y146990D02*
X612822Y144812D01*
G01X612192Y146022D02*
X612193D01*
G01X612822Y144812D02*
X612418Y144741D01*
G01X610624Y145746D02*
X612192Y146022D01*
G01X612109Y144687D02*
X607067Y143798D01*
G01X612418Y144741D02*
X612109Y144687D01*
G01X612822Y144812D02*
X612418Y144741D01*
G01X606557Y145029D02*
X610624Y145746D01*
G01X612109Y144687D02*
X607067Y143798D01*
G01X634697Y161781D02*
X641489Y163223D01*
G01X635203Y160559D02*
X641737Y161946D01*
G01X621841Y153432D02*
X634697Y161781D01*
G01X622347Y152210D02*
X635203Y160559D01*
G01X609056Y150714D02*
X621841Y153432D01*
G01X609562Y149492D02*
X622347Y152210D01*
G01X633510Y164648D02*
X640907Y166219D01*
G01X634016Y163426D02*
X641155Y164942D01*
G01X621458Y156821D02*
X633510Y164648D01*
G01X621968Y155602D02*
X634016Y163426D01*
G01X606146Y153438D02*
X621458Y156821D01*
G01X606707Y152230D02*
X621968Y155602D01*
G01X612109Y144687D02*
X607067Y143798D01*
G01X610624Y145746D02*
X612192Y146022D01*
G01X606557Y145029D02*
X610624Y145746D01*
G01X612418Y144741D02*
X612109Y144687D01*
G01X610624Y145746D02*
X612192Y146022D01*
G01X612822Y144812D02*
X612418Y144741D01*
G01X612192Y146022D02*
X612193D01*
G01X610624Y145746D02*
X612192Y146022D01*
G01X615000Y146990D02*
X612822Y144812D01*
G01X612193Y146022D02*
X614353Y148182D01*
G01X624282Y148963D02*
X615000Y146990D01*
G01X614353Y148182D02*
X623776Y150185D01*
G01X638370Y158112D02*
X624282Y148963D01*
G01X623776Y150185D02*
X637864Y159334D01*
G01X635203Y160559D02*
X641737Y161946D01*
G01X634697Y161781D02*
X641489Y163223D01*
G01X622347Y152210D02*
X635203Y160559D01*
G01X621841Y153432D02*
X634697Y161781D01*
G01X609562Y149492D02*
X622347Y152210D01*
G01X609056Y150714D02*
X621841Y153432D01*
G01X634016Y163426D02*
X641155Y164942D01*
G01X633510Y164648D02*
X640907Y166219D01*
G01X621968Y155602D02*
X634016Y163426D01*
G01X621458Y156821D02*
X633510Y164648D01*
G01X606707Y152230D02*
X621968Y155602D01*
G01X606146Y153438D02*
X621458Y156821D01*
G01X617251Y168502D02*
X644515Y174308D01*
G01X617784Y167286D02*
X644516Y172978D01*
G01X612530Y165153D02*
X617251Y168502D01*
G01X613063Y163937D02*
X617784Y167286D01*
G01D02*
X644516Y172978D01*
G01X617251Y168502D02*
X644515Y174308D01*
G01X613063Y163937D02*
X617784Y167286D01*
G01X612530Y165153D02*
X617251Y168502D01*
G01X633657Y322668D02*
X650256Y344981D01*
G01X632614Y323444D02*
X649352Y345945D01*
G01X628017Y319835D02*
G03X633657Y322668I1J7029D01*
G01X628018Y321135D02*
G03X632614Y323444I0J5729D01*
G01D02*
X649352Y345945D01*
G01X633657Y322668D02*
X650256Y344981D01*
G01X628018Y321135D02*
G03X632614Y323444I0J5729D01*
G01X628017Y319835D02*
G03X633657Y322668I1J7029D01*
G01X613862Y478963D02*
G02X613727Y479098I316J451D01*
G01X612662Y478352D02*
G03X613116Y477898I1516J1062D01*
G01X639229Y461202D02*
X613862Y478963D01*
G01X613116Y477898D02*
X638296Y460268D01*
G01X613116Y477898D02*
X638296Y460268D01*
G01X639229Y461202D02*
X613862Y478963D01*
G01X612662Y478352D02*
G03X613116Y477898I1516J1062D01*
G01X613862Y478963D02*
G02X613727Y479098I316J451D01*
G01X643459Y525968D02*
X621731Y556999D01*
G01X622665Y557933D02*
X759778Y362113D01*
G01X622665Y557933D02*
X759778Y362113D01*
G01X622665Y557933D02*
X759778Y362113D01*
G01X643459Y525968D02*
X621731Y556999D01*
G01X764949Y361504D02*
X625292Y560956D01*
G01X626226Y561890D02*
X766180Y362014D01*
G01X626226Y561890D02*
X766180Y362014D01*
G01X764949Y361504D02*
X625292Y560956D01*
G01X632807Y563786D02*
X806036Y316390D01*
G01X633807Y564626D02*
X807267Y316900D01*
G01X631921Y564672D02*
X632807Y563786D01*
G01X632760Y565672D02*
X633807Y564626D01*
G01X634658Y566481D02*
X809363Y316976D01*
G01X635592Y567415D02*
X810594Y317486D01*
G01X633807Y564626D02*
X807267Y316900D01*
G01X632807Y563786D02*
X806036Y316390D01*
G01X632760Y565672D02*
X633807Y564626D01*
G01X631921Y564672D02*
X632807Y563786D01*
G01X635592Y567415D02*
X810594Y317486D01*
G01X634658Y566481D02*
X809363Y316976D01*
G01X609193Y805526D02*
X659372Y755347D01*
G01X610493Y806065D02*
X660211Y756347D01*
G01X610493Y806065D02*
X660211Y756347D01*
G01X609193Y805526D02*
X659372Y755347D01*
G01X623819Y770420D02*
X621097Y774308D01*
G01X624888Y771162D02*
X622162Y775054D01*
G01X624982Y771025D02*
X624888Y771162D01*
G01X623929Y770260D02*
X623819Y770420D01*
G01X624888Y771162D02*
X622162Y775054D01*
G01X913600Y392061D02*
X623929Y770260D01*
G01X914991Y392384D02*
X624982Y771025D01*
G01X624888Y771162D02*
X622162Y775054D01*
G01X623819Y770420D02*
X621097Y774308D01*
G01X623929Y770260D02*
X623819Y770420D01*
G01X624982Y771025D02*
X624888Y771162D01*
G01X623819Y770420D02*
X621097Y774308D01*
G01X914991Y392384D02*
X624982Y771025D01*
G01X913600Y392061D02*
X623929Y770260D01*
G01X635487Y797826D02*
X621792Y817385D01*
G01X636421Y798760D02*
X623092Y817795D01*
G01X656566Y783066D02*
X635487Y797826D01*
G01X657500Y784000D02*
X636421Y798760D01*
G01D02*
X623092Y817795D01*
G01X635487Y797826D02*
X621792Y817385D01*
G01X657500Y784000D02*
X636421Y798760D01*
G01X656566Y783066D02*
X635487Y797826D01*
G01X609193Y828007D02*
Y805526D01*
G01X610493Y828007D02*
Y806065D01*
G01Y828007D02*
Y806065D01*
G01X609193Y828007D02*
Y805526D01*
G01X634390Y820117D02*
Y828007D01*
G01X635690Y820656D02*
Y828007D01*
G01X659142Y795365D02*
X634390Y820117D01*
G01X659981Y796365D02*
X635690Y820656D01*
G01D02*
Y828007D01*
G01X634390Y820117D02*
Y828007D01*
G01X659981Y796365D02*
X635690Y820656D01*
G01X659142Y795365D02*
X634390Y820117D01*
G01X621792Y817385D02*
Y828007D01*
G01X623092Y817795D02*
Y828007D01*
G01Y817795D02*
Y828007D01*
G01X621792Y817385D02*
Y828007D01*
G01X653882Y152879D02*
X684397Y131512D01*
G01X653882Y152879D02*
X684397Y131512D01*
G01X641218Y141646D02*
X638975D01*
G01X643228Y140812D02*
G03X641218Y141646I-2012J-2010D01*
G01X645905Y140817D02*
G02X644148Y141732I571J3242D01*
G01X645679Y139536D02*
G02X643228Y140812I797J4522D01*
G01X662342Y137918D02*
X645905Y140817D01*
G01X661855Y136683D02*
X645679Y139536D01*
G01X683092Y124423D02*
X662342Y137918D01*
G01X663238Y135783D02*
X661855Y136683D01*
G01X667178Y133221D02*
X665795Y134121D01*
G01X671118Y130659D02*
X669735Y131558D01*
G01X659453Y145564D02*
X682785Y129227D01*
G01X658800Y144433D02*
X682275Y127996D01*
G01X641218Y141646D02*
X638975D01*
G01X643228Y140812D02*
G03X641218Y141646I-2012J-2010D01*
G01X645679Y139536D02*
G02X643228Y140812I797J4522D01*
G01X645905Y140817D02*
G02X644148Y141732I571J3242D01*
G01X661855Y136683D02*
X645679Y139536D01*
G01X662342Y137918D02*
X645905Y140817D01*
G01X663238Y135783D02*
X661855Y136683D01*
G01X683092Y124423D02*
X662342Y137918D01*
G01X667178Y133221D02*
X665795Y134121D01*
G01X683092Y124423D02*
X662342Y137918D01*
G01X671118Y130659D02*
X669735Y131558D01*
G01X683092Y124423D02*
X662342Y137918D01*
G01X683092Y124423D02*
X662342Y137918D01*
G01X658800Y144433D02*
X682275Y127996D01*
G01X659453Y145564D02*
X682785Y129227D01*
G01X684907Y132743D02*
X654404Y154101D01*
G01X643213Y155003D02*
X653882Y152879D01*
G01X654404Y154101D02*
X643190Y156334D01*
G01X640545Y154374D02*
X643213Y155003D01*
G01X643190Y156334D02*
X639957Y155572D01*
G01X639404Y153450D02*
X640545Y154374D01*
G01X639957Y155572D02*
X638585Y154461D01*
G01X639200Y153022D02*
G02X639404Y153450I551J0D01*
G01X638585Y154461D02*
G03X637900Y153022I1167J-1438D01*
G01X639200Y151162D02*
Y153022D01*
G01X637900D02*
Y151162D01*
G01Y153022D02*
Y151162D01*
G01X639200D02*
Y153022D01*
G01X638585Y154461D02*
G03X637900Y153022I1167J-1438D01*
G01X639200D02*
G02X639404Y153450I551J0D01*
G01X639957Y155572D02*
X638585Y154461D01*
G01X639404Y153450D02*
X640545Y154374D01*
G01X643190Y156334D02*
X639957Y155572D01*
G01X640545Y154374D02*
X643213Y155003D01*
G01X654404Y154101D02*
X643190Y156334D01*
G01X643213Y155003D02*
X653882Y152879D01*
G01X684907Y132743D02*
X654404Y154101D01*
G01X641217Y142946D02*
X638975D01*
G01X644148Y141732D02*
G03X641217Y142946I-2931J-2931D01*
G01X655761Y146774D02*
X659306Y145636D01*
G01X655475Y145500D02*
X658800Y144433D01*
G01X641217Y142946D02*
X638975D01*
G01X644148Y141732D02*
G03X641217Y142946I-2931J-2931D01*
G01X655475Y145500D02*
X658800Y144433D01*
G01X655761Y146774D02*
X659306Y145636D01*
G01X665718Y165650D02*
X683912Y153834D01*
G01X665212Y164428D02*
X683406Y152612D01*
G01X644013Y170263D02*
X665718Y165650D01*
G01X644013Y168933D02*
X665212Y164428D01*
G01D02*
X683406Y152612D01*
G01X665718Y165650D02*
X683912Y153834D01*
G01X644013Y168933D02*
X665212Y164428D01*
G01X644013Y170263D02*
X665718Y165650D01*
G01X656578Y157748D02*
X687057Y136406D01*
G01X686547Y135175D02*
X656049Y156531D01*
G01X643623Y160500D02*
X656578Y157748D01*
G01X656049Y156531D02*
X643600Y159175D01*
G01X642071Y160227D02*
X643623Y160500D01*
G01X643600Y159175D02*
X642319Y158950D01*
G01X640075Y159803D02*
X642071Y160227D01*
G01X642319Y158950D02*
X638370Y158112D01*
G01X638101Y159384D02*
X640075Y159803D01*
G01X642319Y158950D02*
X638370Y158112D01*
G01X637864Y159334D02*
X638101Y159385D01*
G01X642319Y158950D02*
X638370Y158112D01*
G01X667714Y155232D02*
X689559Y139937D01*
G01X666987Y154154D02*
X689049Y138706D01*
G01X660232Y160091D02*
X667714Y155232D01*
G01X659726Y158869D02*
X666987Y154154D01*
G01X643677Y163609D02*
X660232Y160091D01*
G01X643654Y162284D02*
X659726Y158869D01*
G01X641489Y163223D02*
X643677Y163609D01*
G01X641737Y161946D02*
X643654Y162284D01*
G01X665086Y162179D02*
X691791Y143480D01*
G01X664557Y160962D02*
X691281Y142249D01*
G01X643731Y166717D02*
X665086Y162179D01*
G01X643708Y165392D02*
X664557Y160962D01*
G01X640907Y166219D02*
X643731Y166717D01*
G01X641155Y164942D02*
X643708Y165392D01*
G01X642319Y158950D02*
X638370Y158112D01*
G01X640075Y159803D02*
X642071Y160227D01*
G01X638101Y159384D02*
X640075Y159803D01*
G01X637864Y159334D02*
X638101Y159385D01*
G01X643600Y159175D02*
X642319Y158950D01*
G01X642071Y160227D02*
X643623Y160500D01*
G01X656049Y156531D02*
X643600Y159175D01*
G01X643623Y160500D02*
X656578Y157748D01*
G01X686547Y135175D02*
X656049Y156531D01*
G01X656578Y157748D02*
X687057Y136406D01*
G01X666987Y154154D02*
X689049Y138706D01*
G01X667714Y155232D02*
X689559Y139937D01*
G01X659726Y158869D02*
X666987Y154154D01*
G01X660232Y160091D02*
X667714Y155232D01*
G01X643654Y162284D02*
X659726Y158869D01*
G01X643677Y163609D02*
X660232Y160091D01*
G01X641737Y161946D02*
X643654Y162284D01*
G01X641489Y163223D02*
X643677Y163609D01*
G01X664557Y160962D02*
X691281Y142249D01*
G01X665086Y162179D02*
X691791Y143480D01*
G01X643708Y165392D02*
X664557Y160962D01*
G01X643731Y166717D02*
X665086Y162179D01*
G01X641155Y164942D02*
X643708Y165392D01*
G01X640907Y166219D02*
X643731Y166717D01*
G01X669059Y169104D02*
X676355Y164367D01*
G01X668553Y167882D02*
X675868Y163132D01*
G01X644515Y174308D02*
X669059Y169104D01*
G01X644516Y172978D02*
X668553Y167882D01*
G01D02*
X675868Y163132D01*
G01X669059Y169104D02*
X676355Y164367D01*
G01X644516Y172978D02*
X668553Y167882D01*
G01X644515Y174308D02*
X669059Y169104D01*
G01X670856Y172570D02*
X679598Y166894D01*
G01X679111Y165659D02*
X670350Y171348D01*
G01X644947Y178077D02*
X670856Y172570D01*
G01X670350Y171348D02*
X644947Y176747D01*
G01X673569Y174017D02*
X643520Y180402D01*
G01X670350Y171348D02*
X644947Y176747D01*
G01Y178077D02*
X670856Y172570D01*
G01X679111Y165659D02*
X670350Y171348D01*
G01X670856Y172570D02*
X679598Y166894D01*
G01X673569Y174017D02*
X643520Y180402D01*
G01X644201Y185231D02*
X675342Y178609D01*
G01X674597Y177438D02*
X644201Y183901D01*
G01X674597Y177438D02*
X644201Y183901D01*
G01Y185231D02*
X675342Y178609D01*
G01X643520Y181732D02*
X674075Y175239D01*
G01X643520Y181732D02*
X674075Y175239D01*
G01X666060Y324506D02*
X674827Y326052D01*
G01X665965Y323168D02*
X683913Y326333D01*
G01X648361Y327592D02*
X665870Y324506D01*
G01X648200Y326300D02*
X665965Y323168D01*
G01X644954Y327600D02*
X648266D01*
G01X644954Y326300D02*
X648200D01*
G01X642511Y326589D02*
G02X644954Y327600I2442J-2443D01*
G01X643431Y325669D02*
G02X644954Y326300I1523J-1522D01*
G01X642800Y324146D02*
G02X643431Y325669I2153J0D01*
G01X641500Y324146D02*
G02X642511Y326589I3454J1D01*
G01X643431Y325669D02*
G02X644954Y326300I1523J-1522D01*
G01X642800Y324146D02*
G02X643431Y325669I2153J0D01*
G01X641500Y323794D02*
Y324146D01*
G01X642800Y323794D02*
Y324146D01*
G01X665965Y323168D02*
X683913Y326333D01*
G01X666060Y324506D02*
X674827Y326052D01*
G01X648200Y326300D02*
X665965Y323168D01*
G01X648361Y327592D02*
X665870Y324506D01*
G01X644954Y326300D02*
X648200D01*
G01X644954Y327600D02*
X648266D01*
G01X643431Y325669D02*
G02X644954Y326300I1523J-1522D01*
G01X642511Y326589D02*
G02X644954Y327600I2442J-2443D01*
G01X641500Y324146D02*
G02X642511Y326589I3454J1D01*
G01X642800Y324146D02*
G02X643431Y325669I2153J0D01*
G01X642511Y326589D02*
G02X644954Y327600I2442J-2443D01*
G01X641500Y324146D02*
G02X642511Y326589I3454J1D01*
G01X642800Y323794D02*
Y324146D01*
G01X641500Y323794D02*
Y324146D01*
G01X657918Y349957D02*
X659287D01*
G01X657532Y351257D02*
X659301D01*
G01X649352Y345945D02*
X657532Y351257D01*
G01X650256Y344981D02*
X657918Y349957D01*
G01X649352Y345945D02*
X657532Y351257D01*
G01D02*
X659301D01*
G01X657918Y349957D02*
X659287D01*
G01X649352Y345945D02*
X657532Y351257D01*
G01X657918Y349957D02*
X659287D01*
G01X650256Y344981D02*
X657918Y349957D01*
G01X679037Y404523D02*
X639229Y461202D01*
G01X638296Y460268D02*
X677972Y403777D01*
G01X638296Y460268D02*
X677972Y403777D01*
G01X679037Y404523D02*
X639229Y461202D01*
G01X758546Y361604D02*
X645255Y523404D01*
G01X758546Y361604D02*
X645255Y523404D01*
G01X827661Y319130D02*
X647113Y576956D01*
G01X826430Y318620D02*
X646179Y576022D01*
G01X823937Y315182D02*
X644066Y572066D01*
G01X825168Y315692D02*
X645000Y573000D01*
G01X826430Y318620D02*
X646179Y576022D01*
G01X827661Y319130D02*
X647113Y576956D01*
G01X825168Y315692D02*
X645000Y573000D01*
G01X823937Y315182D02*
X644066Y572066D01*
G01X821959Y311705D02*
X639686Y572018D01*
G01X820728Y311195D02*
X638752Y571084D01*
G01X820728Y311195D02*
X638752Y571084D01*
G01X821959Y311705D02*
X639686Y572018D01*
G01X656566Y591566D02*
X843446Y324674D01*
G01X657500Y592500D02*
X844677Y325184D01*
G01X659066Y595066D02*
X848977Y323845D01*
G01X657500Y592500D02*
X844677Y325184D01*
G01X656566Y591566D02*
X843446Y324674D01*
G01X659066Y595066D02*
X848977Y323845D01*
G01X653814Y589015D02*
X841280Y321285D01*
G01X652880Y588081D02*
X840049Y320775D01*
G01X836241Y319498D02*
X650116Y585314D01*
G01X837472Y320008D02*
X651050Y586248D01*
G01X652880Y588081D02*
X840049Y320775D01*
G01X653814Y589015D02*
X841280Y321285D01*
G01X837472Y320008D02*
X651050Y586248D01*
G01X836241Y319498D02*
X650116Y585314D01*
G01X831426Y318344D02*
X649444Y578236D01*
G01X832657Y318854D02*
X650378Y579170D01*
G01X832657Y318854D02*
X650378Y579170D01*
G01X831426Y318344D02*
X649444Y578236D01*
G01X669452Y615374D02*
X854184Y351549D01*
G01X669452Y615374D02*
X854184Y351549D01*
G01X660000Y596000D02*
X850208Y324355D01*
G01X666976Y608769D02*
X851219Y345643D01*
G01X667910Y609703D02*
X852450Y346153D01*
G01X660000Y596000D02*
X850208Y324355D01*
G01X667910Y609703D02*
X852450Y346153D01*
G01X666976Y608769D02*
X851219Y345643D01*
G01X650116Y585314D02*
X648205Y586652D01*
G01X651050Y586248D02*
X648951Y587717D01*
G01X651050Y586248D02*
X648951Y587717D01*
G01X650116Y585314D02*
X648205Y586652D01*
G01X670386Y616308D02*
X855415Y352059D01*
G01X670386Y616308D02*
X855415Y352059D01*
G01X650652Y700942D02*
X889104Y360397D01*
G01X651586Y701876D02*
X890335Y360907D01*
G01X651152Y709094D02*
X893252Y363340D01*
G01X651586Y701876D02*
X890335Y360907D01*
G01X650652Y700942D02*
X889104Y360397D01*
G01X651152Y709094D02*
X893252Y363340D01*
G01X648496Y693450D02*
X886700Y353259D01*
G01X649430Y694384D02*
X887931Y353769D01*
G01X649430Y694384D02*
X887931Y353769D01*
G01X648496Y693450D02*
X886700Y353259D01*
G01X883864Y348329D02*
X647149Y686392D01*
G01X648083Y687326D02*
X885095Y348839D01*
G01X648083Y687326D02*
X885095Y348839D01*
G01X883864Y348329D02*
X647149Y686392D01*
G01X652086Y710028D02*
X894483Y363850D01*
G01X652086Y710028D02*
X894483Y363850D01*
G01X659372Y755347D02*
X678838Y741716D01*
G01X660211Y756347D02*
X679772Y742650D01*
G01X660211Y756347D02*
X679772Y742650D01*
G01X659372Y755347D02*
X678838Y741716D01*
G01X918551Y427747D02*
X663066Y792617D01*
G01X918551Y427747D02*
X663066Y792617D01*
G01X918180Y409441D02*
X656566Y783066D01*
G01X919402Y409964D02*
X657500Y784000D01*
G01X919402Y409964D02*
X657500Y784000D01*
G01X918180Y409441D02*
X656566Y783066D01*
G01X927357Y448732D02*
X669035Y817659D01*
G01X656437Y824144D02*
X925627Y439699D01*
G01X657737Y824554D02*
X926858Y440209D01*
G01X927357Y448732D02*
X669035Y817659D01*
G01X657737Y824554D02*
X926858Y440209D01*
G01X656437Y824144D02*
X925627Y439699D01*
G01X663066Y792617D02*
X659142Y795365D01*
G01X664000Y793551D02*
X659981Y796365D01*
G01X919773Y428269D02*
X664000Y793551D01*
G01D02*
X659981Y796365D01*
G01X663066Y792617D02*
X659142Y795365D01*
G01X919773Y428269D02*
X664000Y793551D01*
G01X670335Y818069D02*
Y828600D01*
G01X669035Y817659D02*
Y828600D01*
G01X928579Y449255D02*
X670335Y818069D01*
G01X656437Y828007D02*
Y824144D01*
G01X657737Y828007D02*
Y824554D01*
G01X669035Y817659D02*
Y828600D01*
G01X670335Y818069D02*
Y828600D01*
G01X928579Y449255D02*
X670335Y818069D01*
G01X657737Y828007D02*
Y824554D01*
G01X656437Y828007D02*
Y824144D01*
G01X684397Y131512D02*
X709040Y127166D01*
G01X709050Y128486D02*
X684907Y132743D01*
G01X709050Y128486D02*
X684907Y132743D01*
G01X684397Y131512D02*
X709040Y127166D01*
G01X682605Y123188D02*
X673675Y128996D01*
G01X705982Y120388D02*
X683092Y124423D01*
G01X705982Y119067D02*
X682605Y123188D01*
G01X682785Y129227D02*
X708633Y124671D01*
G01X700790Y124732D02*
X708637Y123349D01*
G01X696161Y125548D02*
X697786Y125262D01*
G01X691532Y126364D02*
X693157Y126078D01*
G01X686904Y127180D02*
X688529Y126894D01*
G01X682275Y127996D02*
X683900Y127710D01*
G01X682605Y123188D02*
X673675Y128996D01*
G01X705982Y119067D02*
X682605Y123188D01*
G01X705982Y120388D02*
X683092Y124423D01*
G01X700790Y124732D02*
X708637Y123349D01*
G01X682785Y129227D02*
X708633Y124671D01*
G01X696161Y125548D02*
X697786Y125262D01*
G01X682785Y129227D02*
X708633Y124671D01*
G01X691532Y126364D02*
X693157Y126078D01*
G01X682785Y129227D02*
X708633Y124671D01*
G01X686904Y127180D02*
X688529Y126894D01*
G01X682785Y129227D02*
X708633Y124671D01*
G01X682275Y127996D02*
X683900Y127710D01*
G01X682785Y129227D02*
X708633Y124671D01*
G01X687057Y136406D02*
X709250Y132494D01*
G01Y131173D02*
X686547Y135175D01*
G01X689559Y139937D02*
X709250Y136466D01*
G01X689049Y138706D02*
X709250Y135145D01*
G01X691791Y143480D02*
X710204Y140234D01*
G01X691281Y142249D02*
X710204Y138913D01*
G01X709250Y131173D02*
X686547Y135175D01*
G01X687057Y136406D02*
X709250Y132494D01*
G01X689049Y138706D02*
X709250Y135145D01*
G01X689559Y139937D02*
X709250Y136466D01*
G01X691281Y142249D02*
X710204Y138913D01*
G01X691791Y143480D02*
X710204Y140234D01*
G01X683912Y153834D02*
X731507Y143717D01*
G01X683406Y152612D02*
X731507Y142387D01*
G01X683406Y152612D02*
X731507Y142387D01*
G01X683912Y153834D02*
X731507Y143717D01*
G01X684572Y172489D02*
X755660Y159966D01*
G01Y158645D02*
X684086Y171254D01*
G01X675485Y178389D02*
X684572Y172489D01*
G01X684086Y171254D02*
X674663Y177372D01*
G01X684086Y171254D02*
X674663Y177372D01*
G01X675485Y178389D02*
X684572Y172489D01*
G01X755660Y158645D02*
X684086Y171254D01*
G01X684572Y172489D02*
X755660Y159966D01*
G01X676355Y164367D02*
X760879Y149444D01*
G01X675868Y163132D02*
X704029Y158160D01*
G01X676355Y164367D02*
X760879Y149444D01*
G01X676355Y164367D02*
X760879Y149444D01*
G01X676355Y164367D02*
X760879Y149444D01*
G01X676355Y164367D02*
X760879Y149444D01*
G01X675868Y163132D02*
X704029Y158160D01*
G01X676355Y164367D02*
X760879Y149444D01*
G01X679598Y166894D02*
X758999Y152875D01*
G01Y151554D02*
X679111Y165659D01*
G01X683000Y169443D02*
X756767Y156419D01*
G01Y155098D02*
X682513Y168208D01*
G01X674075Y175239D02*
X683000Y169443D01*
G01X682513Y168208D02*
X673569Y174017D01*
G01X758999Y151554D02*
X679111Y165659D01*
G01X679598Y166894D02*
X758999Y152875D01*
G01X682513Y168208D02*
X673569Y174017D01*
G01X674075Y175239D02*
X683000Y169443D01*
G01X756767Y155098D02*
X682513Y168208D01*
G01X683000Y169443D02*
X756767Y156419D01*
G01X701411Y330739D02*
X738408Y324215D01*
G01X701411Y329418D02*
X737898Y322984D01*
G01X674827Y326052D02*
X701411Y330739D01*
G01X683913Y326333D02*
X701411Y329418D01*
G01D02*
X737898Y322984D01*
G01X701411Y330739D02*
X738408Y324215D01*
G01X683913Y326333D02*
X701411Y329418D01*
G01X674827Y326052D02*
X701411Y330739D01*
G01X679343Y403784D02*
G03X679037Y404523I-1822J-321D01*
G01X677972Y403777D02*
G02X678062Y403558I-451J-313D01*
G01X682500Y385880D02*
X679343Y403784D01*
G01X678062Y403558D02*
X681200Y385766D01*
G01X682500Y379818D02*
Y385880D01*
G01X681200Y385766D02*
Y379818D01*
G01Y385766D02*
Y379818D01*
G01X682500D02*
Y385880D01*
G01X678062Y403558D02*
X681200Y385766D01*
G01X682500Y385880D02*
X679343Y403784D01*
G01X677972Y403777D02*
G02X678062Y403558I-451J-313D01*
G01X679343Y403784D02*
G03X679037Y404523I-1822J-321D01*
G01X672103Y620518D02*
X858758Y353947D01*
G01X673037Y621452D02*
X859989Y354457D01*
G01X673037Y621452D02*
X859989Y354457D01*
G01X672103Y620518D02*
X858758Y353947D01*
G01X870138Y347336D02*
X676759Y623509D01*
G01X677693Y624443D02*
X871369Y347846D01*
G01X678594Y630392D02*
X878541Y344838D01*
G01X879763Y345361D02*
X679528Y631326D01*
G01X677693Y624443D02*
X871369Y347846D01*
G01X870138Y347336D02*
X676759Y623509D01*
G01X879763Y345361D02*
X679528Y631326D01*
G01X678594Y630392D02*
X878541Y344838D01*
G01X678838Y741716D02*
X915284Y404038D01*
G01X679772Y742650D02*
X916506Y404561D01*
G01X679772Y742650D02*
X916506Y404561D01*
G01X678838Y741716D02*
X915284Y404038D01*
G01X681700Y818103D02*
X934878Y456526D01*
G01X683000Y818514D02*
X936100Y457049D01*
G01X694200Y806210D02*
Y828600D01*
G01X695500Y806620D02*
Y828600D01*
G01X938778Y456915D02*
X694200Y806210D01*
G01X940000Y457438D02*
X695500Y806620D01*
G01X683000Y818514D02*
X936100Y457049D01*
G01X681700Y818103D02*
X934878Y456526D01*
G01X695500Y806620D02*
Y828600D01*
G01X694200Y806210D02*
Y828600D01*
G01X940000Y457438D02*
X695500Y806620D01*
G01X938778Y456915D02*
X694200Y806210D01*
G01X681700Y827848D02*
Y818103D01*
G01X683000Y828167D02*
Y818514D01*
G01Y828167D02*
Y818514D01*
G01X681700Y827848D02*
Y818103D01*
G01X732339Y81178D02*
X759148Y86867D01*
G01Y85537D02*
X728972Y79134D01*
G01X732340Y81178D02*
X732339D01*
G01X759148Y85537D02*
X728972Y79134D01*
G01X728835Y80434D02*
X732340Y81178D01*
G01X759148Y85537D02*
X728972Y79134D01*
G01X722089Y80434D02*
X728835D01*
G01X728972Y79134D02*
X722028D01*
G01X730304Y85099D02*
X739327Y87004D01*
G01X730197Y83747D02*
X739752Y85765D01*
G01X727786Y86736D02*
X730304Y85099D01*
G01X726626Y85939D02*
X730046Y83715D01*
G01X726304Y93706D02*
X727786Y86736D01*
G01X725112Y93059D02*
X726626Y85939D01*
G01X725462Y94548D02*
X726304Y93706D01*
G01X724543Y93628D02*
X725112Y93059D01*
G01X725152Y94817D02*
G02X725462Y94548I-1747J-2326D01*
G01X724372Y93776D02*
G02X724543Y93628I-964J-1287D01*
G01X723979Y93993D02*
G02X724372Y93776I-580J-1515D01*
G01X724444Y95208D02*
G02X725152Y94817I-1045J-2729D01*
G01X724372Y93776D02*
G02X724543Y93628I-964J-1287D01*
G01X723979Y93993D02*
G02X724372Y93776I-580J-1515D01*
G01X723400Y94100D02*
G02X723979Y93993I0J-1622D01*
G01X723400Y95400D02*
G02X724444Y95208I2J-2923D01*
G01X723979Y93993D02*
G02X724372Y93776I-580J-1515D01*
G01X723400Y94100D02*
G02X723979Y93993I0J-1622D01*
G01X722500Y95400D02*
X723400D01*
G01X722500Y94100D02*
X723400D01*
G01X735629Y93962D02*
X740597Y95018D01*
G01X735458Y92596D02*
X741103Y93796D01*
G01X729943Y96767D02*
X735629Y93962D01*
G01X728923Y95820D02*
X735458Y92596D01*
G01X727775Y102135D02*
X729943Y96767D01*
G01X726685Y101362D02*
X728923Y95820D01*
G01X725200Y104400D02*
X727775Y102135D01*
G01X724709Y103100D02*
X726685Y101362D01*
G01X721984Y104400D02*
X725200D01*
G01X722394Y103100D02*
X724709D01*
G01X738814Y100601D02*
X734058D01*
G01Y99301D02*
X739157D01*
G01X728972Y79134D02*
X722028D01*
G01X722089Y80434D02*
X728835D01*
G01X759148Y85537D02*
X728972Y79134D01*
G01X732339Y81178D02*
X759148Y86867D01*
G01X732340Y81178D02*
X732339D01*
G01X728835Y80434D02*
X732340Y81178D01*
G01X730197Y83747D02*
X739752Y85765D01*
G01X730304Y85099D02*
X739327Y87004D01*
G01X726626Y85939D02*
X730046Y83715D01*
G01X727786Y86736D02*
X730304Y85099D01*
G01X725112Y93059D02*
X726626Y85939D01*
G01X726304Y93706D02*
X727786Y86736D01*
G01X724543Y93628D02*
X725112Y93059D01*
G01X725462Y94548D02*
X726304Y93706D01*
G01X724372Y93776D02*
G02X724543Y93628I-964J-1287D01*
G01X725152Y94817D02*
G02X725462Y94548I-1747J-2326D01*
G01X724444Y95208D02*
G02X725152Y94817I-1045J-2729D01*
G01X723979Y93993D02*
G02X724372Y93776I-580J-1515D01*
G01X725152Y94817D02*
G02X725462Y94548I-1747J-2326D01*
G01X724444Y95208D02*
G02X725152Y94817I-1045J-2729D01*
G01X723400Y95400D02*
G02X724444Y95208I2J-2923D01*
G01X723400Y94100D02*
G02X723979Y93993I0J-1622D01*
G01X724444Y95208D02*
G02X725152Y94817I-1045J-2729D01*
G01X723400Y95400D02*
G02X724444Y95208I2J-2923D01*
G01X722500Y94100D02*
X723400D01*
G01X722500Y95400D02*
X723400D01*
G01X735458Y92596D02*
X741103Y93796D01*
G01X735629Y93962D02*
X740597Y95018D01*
G01X728923Y95820D02*
X735458Y92596D01*
G01X729943Y96767D02*
X735629Y93962D01*
G01X726685Y101362D02*
X728923Y95820D01*
G01X727775Y102135D02*
X729943Y96767D01*
G01X724709Y103100D02*
X726685Y101362D01*
G01X725200Y104400D02*
X727775Y102135D01*
G01X722394Y103100D02*
X724709D01*
G01X721984Y104400D02*
X725200D01*
G01X734058Y99301D02*
X739157D01*
G01X738814Y100601D02*
X734058D01*
G01X737792Y117850D02*
X754508Y114902D01*
G01X737792Y116529D02*
X754072Y113658D01*
G01X727531Y116042D02*
X737792Y117850D01*
G01X727531Y114721D02*
X737792Y116529D01*
G01X725503Y116400D02*
X727531Y116042D01*
G01X725388Y115100D02*
X727531Y114721D01*
G01X722394Y116400D02*
X725503D01*
G01X722394Y115100D02*
X725388D01*
G01X737792Y116529D02*
X754072Y113658D01*
G01X737792Y117850D02*
X754508Y114902D01*
G01X727531Y114721D02*
X737792Y116529D01*
G01X727531Y116042D02*
X737792Y117850D01*
G01X725388Y115100D02*
X727531Y114721D01*
G01X725503Y116400D02*
X727531Y116042D01*
G01X722394Y115100D02*
X725388D01*
G01X722394Y116400D02*
X725503D01*
G01X736525Y128377D02*
X766978Y123005D01*
G01Y124326D02*
X736525Y129698D01*
G01X734127Y127954D02*
X736525Y128377D01*
G01Y129698D02*
X733901Y129235D01*
G01X731299Y127456D02*
X734127Y127954D01*
G01X733901Y129235D02*
X731299Y128777D01*
G01X721000Y129272D02*
X731299Y127456D01*
G01X721226Y130553D02*
X721004Y130592D01*
G01X726264Y129664D02*
X721226Y130553D01*
G01X731299Y128777D02*
X726264Y129664D01*
G01X709040Y127164D02*
X721000Y129272D01*
G01X720886Y130572D02*
X709050Y128486D01*
G01X721226Y130553D02*
X721004Y130592D01*
G01X720886Y130572D02*
X709050Y128486D01*
G01X709040Y127164D02*
X721000Y129272D01*
G01X721226Y130553D02*
X721004Y130592D01*
G01X721000Y129272D02*
X731299Y127456D01*
G01X709040Y127164D02*
X721000Y129272D01*
G01X726264Y129664D02*
X721226Y130553D01*
G01X721000Y129272D02*
X731299Y127456D01*
G01Y128777D02*
X726264Y129664D01*
G01X721000Y129272D02*
X731299Y127456D01*
G01X733901Y129235D02*
X731299Y128777D01*
G01Y127456D02*
X734127Y127954D01*
G01X736525Y129698D02*
X733901Y129235D01*
G01X734127Y127954D02*
X736525Y128377D01*
G01X766978Y124326D02*
X736525Y129698D01*
G01Y128377D02*
X766978Y123005D01*
G01X721128Y123058D02*
X705982Y120388D01*
G01X712816Y120272D02*
X705982Y119067D01*
G01X714524Y120573D02*
X712816Y120272D01*
G01X721128Y121737D02*
X714524Y120573D01*
G01X731222Y121278D02*
X721128Y123058D01*
G01X725769Y120917D02*
X721128Y121737D01*
G01X729254Y120303D02*
X725769Y120917D01*
G01X732963Y120971D02*
X731223Y121277D01*
G01X732963Y119650D02*
X729254Y120303D01*
G01X738089Y121875D02*
X732963Y120971D01*
G01X738089Y120554D02*
X732963Y119650D01*
G01X741798Y121222D02*
X738089Y121875D01*
G01X766210Y115598D02*
X738089Y120554D01*
G01X766210Y115598D02*
X738089Y120554D01*
G01X766210Y115598D02*
X738089Y120554D01*
G01X736421Y124477D02*
X766619Y119143D01*
G01X736647Y125758D02*
X751632Y123112D01*
G01X736421Y124477D02*
X766619Y119143D01*
G01X736421Y125798D02*
X736647Y125759D01*
G01X736421Y124477D02*
X766619Y119143D01*
G01X730592Y123450D02*
X736421Y124477D01*
G01X730592Y124771D02*
X736421Y125798D01*
G01X730592Y123450D02*
X736421Y124477D01*
G01X729255Y125006D02*
X730592Y124771D01*
G01X729030Y123725D02*
X730592Y123450D01*
G01X728587Y125123D02*
X729255Y125006D01*
G01X729030Y123725D02*
X730592Y123450D01*
G01X727694Y123960D02*
X729030Y123725D01*
G01X727920Y125241D02*
X728587Y125123D01*
G01X727694Y123960D02*
X729030Y123725D01*
G01X725022Y124431D02*
X727694Y123960D01*
G01X719903Y126654D02*
X727920Y125241D01*
G01X725022Y124431D02*
X727694Y123960D01*
G01X723270Y124739D02*
X725022Y124431D01*
G01X719903Y125333D02*
X723270Y124739D01*
G01X708633Y124670D02*
X719903Y126654D01*
G01X708637Y123349D02*
X719903Y125333D01*
G01X712816Y120272D02*
X705982Y119067D01*
G01X721128Y123058D02*
X705982Y120388D01*
G01X714524Y120573D02*
X712816Y120272D01*
G01X721128Y123058D02*
X705982Y120388D01*
G01X721128Y121737D02*
X714524Y120573D01*
G01X721128Y123058D02*
X705982Y120388D01*
G01X725769Y120917D02*
X721128Y121737D01*
G01X731222Y121278D02*
X721128Y123058D01*
G01X729254Y120303D02*
X725769Y120917D01*
G01X731222Y121278D02*
X721128Y123058D01*
G01X732963Y119650D02*
X729254Y120303D01*
G01X732963Y120971D02*
X731223Y121277D01*
G01X738089Y120554D02*
X732963Y119650D01*
G01X738089Y121875D02*
X732963Y120971D01*
G01X766210Y115598D02*
X738089Y120554D01*
G01X741798Y121222D02*
X738089Y121875D01*
G01X736421Y124477D02*
X766619Y119143D01*
G01X736647Y125758D02*
X751632Y123112D01*
G01X736421Y125798D02*
X736647Y125759D01*
G01X730592Y123450D02*
X736421Y124477D01*
G01Y125798D02*
X736647Y125759D01*
G01X730592Y124771D02*
X736421Y125798D01*
G01X729030Y123725D02*
X730592Y123450D01*
G01X729255Y125006D02*
X730592Y124771D01*
G01X728587Y125123D02*
X729255Y125006D01*
G01X727694Y123960D02*
X729030Y123725D01*
G01X728587Y125123D02*
X729255Y125006D01*
G01X727920Y125241D02*
X728587Y125123D01*
G01X725022Y124431D02*
X727694Y123960D01*
G01X727920Y125241D02*
X728587Y125123D01*
G01X719903Y126654D02*
X727920Y125241D01*
G01X723270Y124739D02*
X725022Y124431D01*
G01X719903Y126654D02*
X727920Y125241D01*
G01X719903Y125333D02*
X723270Y124739D01*
G01X719903Y126654D02*
X727920Y125241D01*
G01X708637Y123349D02*
X719903Y125333D01*
G01X708633Y124670D02*
X719903Y126654D01*
G01X731551Y132758D02*
X742000Y134601D01*
G01Y133280D02*
X731551Y131437D01*
G01X721150Y134591D02*
X731551Y132758D01*
G01Y131437D02*
X721150Y133270D01*
G01X714975Y133503D02*
X721150Y134591D01*
G01Y133270D02*
X709250Y131173D01*
G01Y132494D02*
X714975Y133503D01*
G01X721150Y133270D02*
X709250Y131173D01*
G01X731750Y136783D02*
X742000Y138589D01*
G01X731750Y135462D02*
X742000Y137268D01*
G01X721400Y138608D02*
X731750Y136783D01*
G01X721400Y137287D02*
X731750Y135462D01*
G01X715100Y137497D02*
X721400Y138608D01*
G01X709250Y135145D02*
X721400Y137287D01*
G01X709250Y136466D02*
X715100Y137497D01*
G01X709250Y135145D02*
X721400Y137287D01*
G01X731850Y140438D02*
X743002Y142403D01*
G01X731850Y139117D02*
X743002Y141082D01*
G01X721605Y142244D02*
X731850Y140438D01*
G01X721605Y140923D02*
X731850Y139117D01*
G01X710204Y140234D02*
X721605Y142244D01*
G01X710204Y138913D02*
X721605Y140923D01*
G01X721150Y133270D02*
X709250Y131173D01*
G01X714975Y133503D02*
X721150Y134591D01*
G01X709250Y132494D02*
X714975Y133503D01*
G01X731551Y131437D02*
X721150Y133270D01*
G01Y134591D02*
X731551Y132758D01*
G01X742000Y133280D02*
X731551Y131437D01*
G01Y132758D02*
X742000Y134601D01*
G01X731750Y135462D02*
X742000Y137268D01*
G01X731750Y136783D02*
X742000Y138589D01*
G01X721400Y137287D02*
X731750Y135462D01*
G01X721400Y138608D02*
X731750Y136783D01*
G01X709250Y135145D02*
X721400Y137287D01*
G01X715100Y137497D02*
X721400Y138608D01*
G01X709250Y136466D02*
X715100Y137497D01*
G01X731850Y139117D02*
X743002Y141082D01*
G01X731850Y140438D02*
X743002Y142403D01*
G01X721605Y140923D02*
X731850Y139117D01*
G01X721605Y142244D02*
X731850Y140438D01*
G01X710204Y138913D02*
X721605Y140923D01*
G01X710204Y140234D02*
X721605Y142244D01*
G01X731507Y143717D02*
X747990Y147221D01*
G01X731507Y142387D02*
X747990Y145891D01*
G01X731507Y142387D02*
X747990Y145891D01*
G01X731507Y143717D02*
X747990Y147221D01*
G01X721233Y155122D02*
X760879Y148123D01*
G01X716526Y155953D02*
X718151Y155667D01*
G01X711818Y156784D02*
X713443Y156498D01*
G01X707111Y157616D02*
X708736Y157329D01*
G01X721233Y155122D02*
X760879Y148123D01*
G01X716526Y155953D02*
X718151Y155667D01*
G01X711818Y156784D02*
X713443Y156498D01*
G01X707111Y157616D02*
X708736Y157329D01*
G01X738408Y324215D02*
X750234Y315934D01*
G01X737898Y322984D02*
X749300Y315000D01*
G01X737898Y322984D02*
X749300Y315000D01*
G01X738408Y324215D02*
X750234Y315934D01*
G01X733042Y768759D02*
X725728Y810237D01*
G01X734273Y769269D02*
X727028Y810353D01*
G01X950578Y458085D02*
X733042Y768759D01*
G01X951800Y458608D02*
X734273Y769269D01*
G01D02*
X727028Y810353D01*
G01X733042Y768759D02*
X725728Y810237D01*
G01X951800Y458608D02*
X734273Y769269D01*
G01X950578Y458085D02*
X733042Y768759D01*
G01X725728Y810237D02*
Y828007D01*
G01X727028Y810353D02*
Y828007D01*
G01Y810353D02*
Y828007D01*
G01X725728Y810237D02*
Y828007D01*
G01X738327Y818678D02*
Y828007D01*
G01X750465Y749833D02*
X738327Y818678D01*
G01D02*
Y828007D01*
G01X750465Y749833D02*
X738327Y818678D01*
G01X767000Y107500D02*
X776400Y110200D01*
G01X763700Y108400D02*
X767000Y107500D01*
G01X763700Y108400D02*
X767000Y107500D01*
G01D02*
X776400Y110200D01*
G01X763700Y108400D02*
X767000Y107500D01*
G01X767461Y85575D02*
X788650Y90080D01*
G01X789156Y88858D02*
X767598Y84275D01*
G01X765223Y85575D02*
X767461D01*
G01X767598Y84275D02*
X765086D01*
G01X759148Y86867D02*
X765223Y85575D01*
G01X765086Y84275D02*
X759148Y85537D01*
G01X763990Y91907D02*
X816493Y103066D01*
G01X763990Y90577D02*
X816493Y101736D01*
G01X750333Y94810D02*
X763990Y91907D01*
G01X750333Y93480D02*
X763990Y90577D01*
G01X746701Y94038D02*
X750333Y94810D01*
G01X747207Y92816D02*
X750333Y93480D01*
G01X741853Y90889D02*
X746701Y94038D01*
G01X742793Y89948D02*
X747207Y92816D01*
G01X739327Y87004D02*
X741853Y90888D01*
G01X740125Y85845D02*
X742793Y89948D01*
G01X758162Y100991D02*
X775056Y97400D01*
G01X758162Y99661D02*
X775056Y96070D01*
G01X745719Y98346D02*
X758162Y100991D01*
G01X746226Y97124D02*
X758162Y99661D01*
G01X740597Y95018D02*
X745719Y98346D01*
G01X745425Y96603D02*
X746226Y97124D01*
G01X745424Y96603D02*
X745425D01*
G01X741103Y93796D02*
X745424Y96603D01*
G01X747146Y105323D02*
X738814Y100601D01*
G01X739157Y99301D02*
X747594Y104082D01*
G01X756140Y106939D02*
X747146Y105323D01*
G01X747594Y104082D02*
X756098Y105610D01*
G01X765277Y104688D02*
X756140Y106939D01*
G01X756098Y105610D02*
X774465Y101084D01*
G01X774419Y102435D02*
X765279Y104687D01*
G01X756098Y105610D02*
X774465Y101084D01*
G01X765086Y84275D02*
X759148Y85537D01*
G01Y86867D02*
X765223Y85575D01*
G01X767598Y84275D02*
X765086D01*
G01X765223Y85575D02*
X767461D01*
G01X789156Y88858D02*
X767598Y84275D01*
G01X767461Y85575D02*
X788650Y90080D01*
G01X763990Y90577D02*
X816493Y101736D01*
G01X763990Y91907D02*
X816493Y103066D01*
G01X750333Y93480D02*
X763990Y90577D01*
G01X750333Y94810D02*
X763990Y91907D01*
G01X747207Y92816D02*
X750333Y93480D01*
G01X746701Y94038D02*
X750333Y94810D01*
G01X742793Y89948D02*
X747207Y92816D01*
G01X741853Y90889D02*
X746701Y94038D01*
G01X740125Y85845D02*
X742793Y89948D01*
G01X739327Y87004D02*
X741853Y90888D01*
G01X758162Y99661D02*
X775056Y96070D01*
G01X758162Y100991D02*
X775056Y97400D01*
G01X746226Y97124D02*
X758162Y99661D01*
G01X745719Y98346D02*
X758162Y100991D01*
G01X745425Y96603D02*
X746226Y97124D01*
G01X740597Y95018D02*
X745719Y98346D01*
G01X745424Y96603D02*
X745425D01*
G01X740597Y95018D02*
X745719Y98346D01*
G01X741103Y93796D02*
X745424Y96603D01*
G01X740597Y95018D02*
X745719Y98346D01*
G01X756098Y105610D02*
X774465Y101084D01*
G01X765277Y104688D02*
X756140Y106939D01*
G01X774419Y102435D02*
X765279Y104687D01*
G01X747594Y104082D02*
X756098Y105610D01*
G01X756140Y106939D02*
X747146Y105323D01*
G01X739157Y99301D02*
X747594Y104082D01*
G01X747146Y105323D02*
X738814Y100601D01*
G01X766991Y108850D02*
X776425Y111560D01*
G01X765591Y109232D02*
X766991Y108850D01*
G01X764190Y109615D02*
X765591Y109232D01*
G01X754508Y114902D02*
X764190Y109615D01*
G01X754072Y113658D02*
X763700Y108400D01*
G01X766991Y108850D02*
X776425Y111560D01*
G01X765591Y109232D02*
X766991Y108850D01*
G01X764190Y109615D02*
X765591Y109232D01*
G01X754072Y113658D02*
X763700Y108400D01*
G01X754508Y114902D02*
X764190Y109615D01*
G01X766978Y123005D02*
X784701Y126131D01*
G01X784475Y127412D02*
X766978Y124326D01*
G01X784475Y127412D02*
X766978Y124326D01*
G01Y123005D02*
X784701Y126131D01*
G01X752376Y119357D02*
X741798Y121222D01*
G01X766216Y116917D02*
X752376Y119357D01*
G01X770997Y117714D02*
X766216Y116917D01*
G01X771210Y116431D02*
X766210Y115598D01*
G01X782400Y119600D02*
X770997Y117714D01*
G01X782333Y118271D02*
X771210Y116431D01*
G01X772137Y121437D02*
X782802Y123338D01*
G01X772364Y120156D02*
X782750Y122008D01*
G01X769377Y120950D02*
X772137Y121437D01*
G01X766619Y119143D02*
X772364Y120156D01*
G01X768407Y120779D02*
X769377Y120950D01*
G01X766619Y119143D02*
X772364Y120156D01*
G01X766619Y120464D02*
X768407Y120779D01*
G01X766619Y119143D02*
X772364Y120156D01*
G01X751632Y123112D02*
X766619Y120464D01*
G01X752376Y119357D02*
X741798Y121222D01*
G01X766216Y116917D02*
X752376Y119357D01*
G01X771210Y116431D02*
X766210Y115598D01*
G01X770997Y117714D02*
X766216Y116917D01*
G01X782333Y118271D02*
X771210Y116431D01*
G01X782400Y119600D02*
X770997Y117714D01*
G01X772364Y120156D02*
X782750Y122008D01*
G01X772137Y121437D02*
X782802Y123338D01*
G01X766619Y119143D02*
X772364Y120156D01*
G01X769377Y120950D02*
X772137Y121437D01*
G01X768407Y120779D02*
X769377Y120950D01*
G01X766619Y120464D02*
X768407Y120779D01*
G01X751632Y123112D02*
X766619Y120464D01*
G01X742000Y134601D02*
X772400Y129241D01*
G01X752882Y131361D02*
X742000Y133280D01*
G01X757511Y130545D02*
X755886Y130832D01*
G01X772400Y127920D02*
X760514Y130016D01*
G01X772298Y133248D02*
X802950Y138651D01*
G01X772298Y131927D02*
X802950Y137330D01*
G01X753975Y136478D02*
X772298Y133248D01*
G01X753749Y135197D02*
X772298Y131927D01*
G01X742000Y138589D02*
X753975Y136478D01*
G01X742000Y137268D02*
X753749Y135197D01*
G01X753701Y140517D02*
X771790Y143705D01*
G01X765536Y141282D02*
X771790Y142384D01*
G01X760908Y140466D02*
X762533Y140753D01*
G01X753701Y139196D02*
X757904Y139937D01*
G01X743002Y142403D02*
X753701Y140517D01*
G01X743002Y141082D02*
X753701Y139196D01*
G01X752882Y131361D02*
X742000Y133280D01*
G01Y134601D02*
X772400Y129241D01*
G01X757511Y130545D02*
X755886Y130832D01*
G01X742000Y134601D02*
X772400Y129241D01*
G01Y127920D02*
X760514Y130016D01*
G01X742000Y134601D02*
X772400Y129241D01*
G01X772298Y131927D02*
X802950Y137330D01*
G01X772298Y133248D02*
X802950Y138651D01*
G01X753749Y135197D02*
X772298Y131927D01*
G01X753975Y136478D02*
X772298Y133248D01*
G01X742000Y137268D02*
X753749Y135197D01*
G01X742000Y138589D02*
X753975Y136478D01*
G01X765536Y141282D02*
X771790Y142384D01*
G01X753701Y140517D02*
X771790Y143705D01*
G01X760908Y140466D02*
X762533Y140753D01*
G01X753701Y140517D02*
X771790Y143705D01*
G01X753701Y139196D02*
X757904Y139937D01*
G01X753701Y140517D02*
X771790Y143705D01*
G01X743002Y141082D02*
X753701Y139196D01*
G01X743002Y142403D02*
X753701Y140517D01*
G01X772198Y147485D02*
X792370Y143929D01*
G01X772198Y146164D02*
X792370Y142608D01*
G01X758627Y145094D02*
X772198Y147485D01*
G01X758627Y143773D02*
X772198Y146164D01*
G01X754914Y145750D02*
X758627Y145094D01*
G01X754666Y144472D02*
X758627Y143773D01*
G01X747990Y147221D02*
X754914Y145749D01*
G01X747990Y145891D02*
X754666Y144472D01*
G01X772198Y146164D02*
X792370Y142608D01*
G01X772198Y147485D02*
X792370Y143929D01*
G01X758627Y143773D02*
X772198Y146164D01*
G01X758627Y145094D02*
X772198Y147485D01*
G01X754666Y144472D02*
X758627Y143773D01*
G01X754914Y145750D02*
X758627Y145094D01*
G01X747990Y145891D02*
X754666Y144472D01*
G01X747990Y147221D02*
X754914Y145749D01*
G01X771790Y143705D02*
X791191Y140286D01*
G01X771790Y142384D02*
X791191Y138965D01*
G01X771790Y142384D02*
X791191Y138965D01*
G01X771790Y143705D02*
X791191Y140286D01*
G01X755660Y159966D02*
X773173Y163053D01*
G01Y161732D02*
X755660Y158645D01*
G01X773173Y161732D02*
X755660Y158645D01*
G01Y159966D02*
X773173Y163053D01*
G01X760879Y149444D02*
X773848Y151730D01*
G01X760879Y148123D02*
X773848Y150409D01*
G01X760879Y148123D02*
X773848Y150409D01*
G01X760879Y149444D02*
X773848Y151730D01*
G01X758999Y152875D02*
X774201Y155555D01*
G01Y154234D02*
X758999Y151554D01*
G01X756767Y156419D02*
X773029Y159286D01*
G01Y157965D02*
X756767Y155098D01*
G01X774201Y154234D02*
X758999Y151554D01*
G01Y152875D02*
X774201Y155555D01*
G01X773029Y157965D02*
X756767Y155098D01*
G01Y156419D02*
X773029Y159286D01*
G01X771518Y220607D02*
X779363Y215115D01*
G01X770585Y219673D02*
X778853Y213884D01*
G01X766900Y227200D02*
X771518Y220607D01*
G01X765669Y226690D02*
X770585Y219673D01*
G01X757333Y281462D02*
X766900Y227200D01*
G01X756012Y281462D02*
X765669Y226690D01*
G01X770585Y219673D02*
X778853Y213884D01*
G01X771518Y220607D02*
X779363Y215115D01*
G01X765669Y226690D02*
X770585Y219673D01*
G01X766900Y227200D02*
X771518Y220607D01*
G01X756012Y281462D02*
X765669Y226690D01*
G01X757333Y281462D02*
X766900Y227200D01*
G01X770564Y230461D02*
X762550Y275900D01*
G01X763850Y276014D02*
X771795Y230971D01*
G01X775536Y223365D02*
X770564Y230461D01*
G01X771795Y230971D02*
X776469Y224299D01*
G01X771795Y230971D02*
X776469Y224299D01*
G01X775536Y223365D02*
X770564Y230461D01*
G01X763850Y276014D02*
X771795Y230971D01*
G01X770564Y230461D02*
X762550Y275900D01*
G01D02*
Y277420D01*
G01X763850Y277306D02*
Y276014D01*
G01Y277306D02*
Y276014D01*
G01X762550Y275900D02*
Y277420D01*
G01X770004Y271854D02*
X768390Y281008D01*
G01X769711D02*
X771235Y272364D01*
G01X773361Y267060D02*
X770004Y271854D01*
G01X771235Y272364D02*
X774295Y267994D01*
G01X771235Y272364D02*
X774295Y267994D01*
G01X773361Y267060D02*
X770004Y271854D01*
G01X769711Y281008D02*
X771235Y272364D01*
G01X770004Y271854D02*
X768390Y281008D01*
G01X758914Y290433D02*
X757333Y281462D01*
G01X757593Y290433D02*
X756012Y281462D01*
G01X755826Y307947D02*
X758914Y290433D01*
G01X754595Y307437D02*
X757593Y290433D01*
G01X750234Y315934D02*
X755826Y307947D01*
G01X749300Y315000D02*
X754595Y307437D01*
G01X757593Y290433D02*
X756012Y281462D01*
G01X758914Y290433D02*
X757333Y281462D01*
G01X754595Y307437D02*
X757593Y290433D01*
G01X755826Y307947D02*
X758914Y290433D01*
G01X749300Y315000D02*
X754595Y307437D01*
G01X750234Y315934D02*
X755826Y307947D01*
G01X767971Y308159D02*
X758547Y361603D01*
G01X759778Y362113D02*
X769292Y308159D01*
G01X762550Y277420D02*
X767971Y308159D01*
G01X769292D02*
X763850Y277306D01*
G01X769292Y308159D02*
X763850Y277306D01*
G01X762550Y277420D02*
X767971Y308159D01*
G01X759778Y362113D02*
X769292Y308159D01*
G01X767971D02*
X758547Y361603D01*
G01X768390Y281008D02*
X773767Y311502D01*
G01X775088D02*
X769711Y281008D01*
G01X775088Y311502D02*
X769711Y281008D01*
G01X768390D02*
X773767Y311502D01*
G01D02*
X764949Y361504D01*
G01X766180Y362014D02*
X775088Y311502D01*
G01X766180Y362014D02*
X775088Y311502D01*
G01X773767D02*
X764949Y361504D01*
G01X763604Y742715D02*
X750925Y814623D01*
G01X764835Y743225D02*
X752225Y814737D01*
G01X958769Y463990D02*
X763604Y742715D01*
G01X960000Y464500D02*
X764835Y743225D01*
G01X955700Y458996D02*
X751696Y750343D01*
G01X954478Y458473D02*
X750465Y749833D01*
G01X764835Y743225D02*
X752225Y814737D01*
G01X763604Y742715D02*
X750925Y814623D01*
G01X960000Y464500D02*
X764835Y743225D01*
G01X958769Y463990D02*
X763604Y742715D01*
G01X954478Y458473D02*
X750465Y749833D01*
G01X955700Y458996D02*
X751696Y750343D01*
G01X775799Y736942D02*
X763524Y806563D01*
G01X777030Y737452D02*
X764824Y806677D01*
G01X777030Y737452D02*
X764824Y806677D01*
G01X775799Y736942D02*
X763524Y806563D01*
G01X751696Y750343D02*
X739627Y818795D01*
G01X751696Y750343D02*
X739627Y818795D01*
G01X763524Y806563D02*
Y828007D01*
G01X764824Y806677D02*
Y828007D01*
G01Y806677D02*
Y828007D01*
G01X763524Y806563D02*
Y828007D01*
G01X750925Y814623D02*
Y828007D01*
G01X752225Y814737D02*
Y828007D01*
G01Y814737D02*
Y828007D01*
G01X750925Y814623D02*
Y828007D01*
G01X739627Y818795D02*
Y828007D01*
G01Y818795D02*
Y828007D01*
G01X808035Y92153D02*
X805723Y93654D01*
G01X802977Y95567D02*
X806229Y94876D01*
G01X805723Y93654D02*
X802977Y94237D01*
G01X793948Y93648D02*
X802977Y95567D01*
G01Y94237D02*
X794745Y92488D01*
G01X788650Y90080D02*
X793805Y93428D01*
G01X794745Y92488D02*
X789156Y88858D01*
G01X775056Y97400D02*
X817086Y106333D01*
G01X775056Y96070D02*
X817086Y105003D01*
G01X808376Y113310D02*
X774419Y102435D01*
G01X774465Y101084D02*
X808452Y111969D01*
G01X794745Y92488D02*
X789156Y88858D01*
G01X788650Y90080D02*
X793805Y93428D01*
G01X802977Y94237D02*
X794745Y92488D01*
G01X793948Y93648D02*
X802977Y95567D01*
G01X805723Y93654D02*
X802977Y94237D01*
G01Y95567D02*
X806229Y94876D01*
G01X808035Y92153D02*
X805723Y93654D01*
G01X775056Y96070D02*
X817086Y105003D01*
G01X775056Y97400D02*
X817086Y106333D01*
G01X774465Y101084D02*
X808452Y111969D01*
G01X808376Y113310D02*
X774419Y102435D01*
G01X782788Y109474D02*
X807976Y117566D01*
G01X782784Y108107D02*
X808052Y116224D01*
G01X776425Y111560D02*
X782788Y109474D01*
G01X776400Y110200D02*
X782784Y108107D01*
G01D02*
X808052Y116224D01*
G01X782788Y109474D02*
X807976Y117566D01*
G01X776400Y110200D02*
X782784Y108107D01*
G01X776425Y111560D02*
X782788Y109474D01*
G01X802907Y129341D02*
X831295Y124337D01*
G01X817326Y128120D02*
X802907Y130662D01*
G01X784701Y126131D02*
X802907Y129341D01*
G01Y130662D02*
X784475Y127412D01*
G01X802907Y130662D02*
X784475Y127412D01*
G01X784701Y126131D02*
X802907Y129341D01*
G01X817326Y128120D02*
X802907Y130662D01*
G01Y129341D02*
X831295Y124337D01*
G01X802907Y129341D02*
X831295Y124337D01*
G01X789085Y117787D02*
X782400Y119600D01*
G01X789116Y116431D02*
X782333Y118271D01*
G01X802311Y122038D02*
X789085Y117787D01*
G01X802387Y120696D02*
X789116Y116431D01*
G01X847600Y112979D02*
X802311Y122038D01*
G01X847600Y111653D02*
X802387Y120696D01*
G01X801975Y126077D02*
X830131Y121111D01*
G01X802056Y124742D02*
X830131Y119790D01*
G01X788310Y121906D02*
X801975Y126077D01*
G01X788338Y120555D02*
X802056Y124742D01*
G01X782802Y123338D02*
X788310Y121906D01*
G01X782750Y122008D02*
X788338Y120555D01*
G01X789116Y116431D02*
X782333Y118271D01*
G01X789085Y117787D02*
X782400Y119600D01*
G01X802387Y120696D02*
X789116Y116431D01*
G01X802311Y122038D02*
X789085Y117787D01*
G01X847600Y111653D02*
X802387Y120696D01*
G01X847600Y112979D02*
X802311Y122038D01*
G01X802056Y124742D02*
X830131Y119790D01*
G01X801975Y126077D02*
X830131Y121111D01*
G01X788338Y120555D02*
X802056Y124742D01*
G01X788310Y121906D02*
X801975Y126077D01*
G01X782750Y122008D02*
X788338Y120555D01*
G01X782802Y123338D02*
X788310Y121906D01*
G01X803401Y134705D02*
X831699Y129717D01*
G01Y128396D02*
X803401Y133384D01*
G01X772400Y129241D02*
X803401Y134705D01*
G01Y133384D02*
X772400Y127920D01*
G01X802950Y137330D02*
X831650Y132272D01*
G01X802950Y138651D02*
X817525Y136082D01*
G01X802950Y137330D02*
X831650Y132272D01*
G01X803202Y141082D02*
X832900Y135846D01*
G01X791191Y140286D02*
X803202Y142403D01*
G01X791191Y138965D02*
X803202Y141082D01*
G01X803401Y133384D02*
X772400Y127920D01*
G01Y129241D02*
X803401Y134705D01*
G01X831699Y128396D02*
X803401Y133384D01*
G01Y134705D02*
X831699Y129717D01*
G01X802950Y137330D02*
X831650Y132272D01*
G01X802950Y138651D02*
X817525Y136082D01*
G01X803202Y141082D02*
X832900Y135846D01*
G01X791191Y138965D02*
X803202Y141082D01*
G01X791191Y140286D02*
X803202Y142403D01*
G01X803624Y145912D02*
X831881Y140930D01*
G01X803624Y144591D02*
X831881Y139609D01*
G01X792370Y143929D02*
X803624Y145912D01*
G01X792370Y142608D02*
X803624Y144591D01*
G01D02*
X831881Y139609D01*
G01X803624Y145912D02*
X831881Y140930D01*
G01X792370Y142608D02*
X803624Y144591D01*
G01X792370Y143929D02*
X803624Y145912D01*
G01X803202Y142403D02*
X832900Y137167D01*
G01X803202Y142403D02*
X832900Y137167D01*
G01X803429Y162102D02*
X832746Y156932D01*
G01Y155611D02*
X803429Y160781D01*
G01X791001Y159911D02*
X803429Y162102D01*
G01Y160781D02*
X791001Y158590D01*
G01X773173Y163053D02*
X791001Y159911D01*
G01Y158590D02*
X773173Y161732D01*
G01X791001Y158590D02*
X773173Y161732D01*
G01Y163053D02*
X791001Y159911D01*
G01X803429Y160781D02*
X791001Y158590D01*
G01Y159911D02*
X803429Y162102D01*
G01X832746Y155611D02*
X803429Y160781D01*
G01Y162102D02*
X832746Y156932D01*
G01X803156Y150268D02*
X832887Y145058D01*
G01X803157Y148948D02*
X832888Y143738D01*
G01X792647Y148418D02*
X803156Y150268D01*
G01X792647Y147097D02*
X803157Y148948D01*
G01X773848Y151730D02*
X792647Y148418D01*
G01X773848Y150409D02*
X792647Y147097D01*
G01X803157Y148948D02*
X832888Y143738D01*
G01X803156Y150268D02*
X832887Y145058D01*
G01X792647Y147097D02*
X803157Y148948D01*
G01X792647Y148418D02*
X803156Y150268D01*
G01X773848Y150409D02*
X792647Y147097D01*
G01X773848Y151730D02*
X792647Y148418D01*
G01X803600Y154286D02*
X833548Y149004D01*
G01Y147683D02*
X803600Y152965D01*
G01X792501Y152329D02*
X803600Y154286D01*
G01Y152965D02*
X792501Y151008D01*
G01X774201Y155555D02*
X792501Y152329D01*
G01Y151008D02*
X774201Y154234D01*
G01X803900Y158205D02*
X834200Y152863D01*
G01Y151542D02*
X803900Y156884D01*
G01X791531Y156024D02*
X803900Y158205D01*
G01Y156884D02*
X791531Y154703D01*
G01X773029Y159286D02*
X791531Y156024D01*
G01Y154703D02*
X773029Y157965D01*
G01X792501Y151008D02*
X774201Y154234D01*
G01Y155555D02*
X792501Y152329D01*
G01X803600Y152965D02*
X792501Y151008D01*
G01Y152329D02*
X803600Y154286D01*
G01X833548Y147683D02*
X803600Y152965D01*
G01Y154286D02*
X833548Y149004D01*
G01X791531Y154703D02*
X773029Y157965D01*
G01Y159286D02*
X791531Y156024D01*
G01X803900Y156884D02*
X791531Y154703D01*
G01Y156024D02*
X803900Y158205D01*
G01X834200Y151542D02*
X803900Y156884D01*
G01Y158205D02*
X834200Y152863D01*
G01X804784Y214741D02*
X808126Y214152D01*
G01X804559Y213460D02*
X807617Y212921D01*
G01X804558Y213460D02*
X804559D01*
G01X801726Y215281D02*
X804784Y214741D01*
G01X804558Y213460D02*
X804559D01*
G01X801500Y214000D02*
X804558Y213460D01*
G01X801500Y215321D02*
X801726Y215282D01*
G01X801500Y214000D02*
X804558Y213460D01*
G01X789846Y211945D02*
X801500Y214000D01*
G01X789846Y213266D02*
X801500Y215321D01*
G01X789846Y211945D02*
X801500Y214000D01*
G01X779363Y215115D02*
X789846Y213266D01*
G01X778853Y213884D02*
X789846Y211945D01*
G01X804559Y213460D02*
X807617Y212921D01*
G01X804784Y214741D02*
X808126Y214152D01*
G01X804558Y213460D02*
X804559D01*
G01X804784Y214741D02*
X808126Y214152D01*
G01X801726Y215281D02*
X804784Y214741D01*
G01X801500Y214000D02*
X804558Y213460D01*
G01X801726Y215281D02*
X804784Y214741D01*
G01X801500Y215321D02*
X801726Y215282D01*
G01X789846Y211945D02*
X801500Y214000D01*
G01Y215321D02*
X801726Y215282D01*
G01X789846Y213266D02*
X801500Y215321D01*
G01X778853Y213884D02*
X789846Y211945D01*
G01X779363Y215115D02*
X789846Y213266D01*
G01X782121Y218755D02*
X775536Y223365D01*
G01X776469Y224299D02*
X782631Y219986D01*
G01X792182Y216981D02*
X782121Y218755D01*
G01X782631Y219986D02*
X792182Y218302D01*
G01X803068Y218901D02*
X792182Y216981D01*
G01Y218302D02*
X803068Y220222D01*
G01X809490Y217769D02*
X803068Y218901D01*
G01Y220222D02*
X810000Y219000D01*
G01X803068Y220222D02*
X810000Y219000D01*
G01X809490Y217769D02*
X803068Y218901D01*
G01X792182Y218302D02*
X803068Y220222D01*
G01Y218901D02*
X792182Y216981D01*
G01X782631Y219986D02*
X792182Y218302D01*
G01Y216981D02*
X782121Y218755D01*
G01X776469Y224299D02*
X782631Y219986D01*
G01X782121Y218755D02*
X775536Y223365D01*
G01X779779Y262566D02*
X773361Y267060D01*
G01X774295Y267994D02*
X780289Y263797D01*
G01X798401Y259283D02*
X779779Y262566D01*
G01X780289Y263797D02*
X798911Y260514D01*
G01X806566Y253566D02*
X798401Y259283D01*
G01X798911Y260514D02*
X807500Y254500D01*
G01X798911Y260514D02*
X807500Y254500D01*
G01X806566Y253566D02*
X798401Y259283D01*
G01X780289Y263797D02*
X798911Y260514D01*
G01X798401Y259283D02*
X779779Y262566D01*
G01X774295Y267994D02*
X780289Y263797D01*
G01X779779Y262566D02*
X773361Y267060D01*
G01X806036Y316390D02*
X810320Y292092D01*
G01X806036Y316390D02*
X810320Y292092D01*
G01X968769Y469990D02*
X789923Y725408D01*
G01X970000Y470500D02*
X791154Y725918D01*
G01X973221Y473275D02*
X801336Y718752D01*
G01X974452Y473785D02*
X802567Y719262D01*
G01X970000Y470500D02*
X791154Y725918D01*
G01X968769Y469990D02*
X789923Y725408D01*
G01X974452Y473785D02*
X802567Y719262D01*
G01X973221Y473275D02*
X801336Y718752D01*
G01X964794Y467034D02*
X775799Y736942D01*
G01X966025Y467544D02*
X777030Y737452D01*
G01X966025Y467544D02*
X777030Y737452D01*
G01X964794Y467034D02*
X775799Y736942D01*
G01X789923Y725408D02*
X775241Y808679D01*
G01X791154Y725918D02*
X776562Y808679D01*
G01X799329Y730135D02*
X790699Y779100D01*
G01X800585Y730501D02*
X792020Y779100D01*
G01X801336Y718752D02*
X799329Y730135D01*
G01X802567Y719262D02*
X800585Y730501D01*
G01X791154Y725918D02*
X776562Y808679D01*
G01X789923Y725408D02*
X775241Y808679D01*
G01X800585Y730501D02*
X792020Y779100D01*
G01X799329Y730135D02*
X790699Y779100D01*
G01X802567Y719262D02*
X800585Y730501D01*
G01X801336Y718752D02*
X799329Y730135D01*
G01X801755Y778089D02*
X804809Y795410D01*
G01X803076Y778089D02*
X806130Y795410D01*
G01X813758Y710019D02*
X801755Y778089D01*
G01X814989Y710529D02*
X803076Y778089D01*
G01D02*
X806130Y795410D01*
G01X801755Y778089D02*
X804809Y795410D01*
G01X814989Y710529D02*
X803076Y778089D01*
G01X813758Y710019D02*
X801755Y778089D01*
G01X790699Y779100D02*
X793679Y796000D01*
G01X792020Y779100D02*
X795000Y796000D01*
G01X792020Y779100D02*
X795000Y796000D01*
G01X790699Y779100D02*
X793679Y796000D01*
G01X801319Y815208D02*
Y828007D01*
G01X802619Y815325D02*
Y828007D01*
G01X804809Y795410D02*
X801319Y815208D01*
G01X806130Y795410D02*
X802619Y815325D01*
G01D02*
Y828007D01*
G01X801319Y815208D02*
Y828007D01*
G01X806130Y795410D02*
X802619Y815325D01*
G01X804809Y795410D02*
X801319Y815208D01*
G01X776122Y813675D02*
Y828007D01*
G01X777422Y813558D02*
Y828007D01*
G01X775241Y808679D02*
X776122Y813675D01*
G01X776562Y808679D02*
X777422Y813558D01*
G01X793679Y796000D02*
X788720Y824129D01*
G01X795000Y796000D02*
X790020Y824246D01*
G01X777422Y813558D02*
Y828007D01*
G01X776122Y813675D02*
Y828007D01*
G01X776562Y808679D02*
X777422Y813558D01*
G01X775241Y808679D02*
X776122Y813675D01*
G01X795000Y796000D02*
X790020Y824246D01*
G01X793679Y796000D02*
X788720Y824129D01*
G01D02*
Y828007D01*
G01X790020Y824246D02*
Y828007D01*
G01Y824246D02*
Y828007D01*
G01X788720Y824129D02*
Y828007D01*
G01X828492Y96928D02*
X848388Y92700D01*
G01X848365Y91375D02*
X828492Y95598D01*
G01X826285Y96459D02*
X828492Y96928D01*
G01Y95598D02*
X826791Y95237D01*
G01X823279Y94507D02*
X826285Y96459D01*
G01X826791Y95237D02*
X824219Y93567D01*
G01X822164Y92790D02*
X823279Y94507D01*
G01X824219Y93567D02*
X823386Y92284D01*
G01X821459Y89468D02*
X822164Y92790D01*
G01X823386Y92284D02*
X822681Y88962D01*
G01X820403Y87845D02*
X821459Y89468D01*
G01X822681Y88962D02*
X821342Y86904D01*
G01X819020Y86950D02*
X820403Y87845D01*
G01X821342Y86904D02*
X819525Y85728D01*
G01X816720Y86461D02*
X819020Y86950D01*
G01X819525Y85728D02*
X816720Y85131D01*
G01X812957Y87261D02*
X816720Y86461D01*
G01Y85131D02*
X812451Y86039D01*
G01X810967Y88553D02*
X812957Y87261D01*
G01X812451Y86039D02*
X810027Y87613D01*
G01X810329Y89536D02*
X810967Y88553D01*
G01X810027Y87613D02*
X809107Y89030D01*
G01X809863Y91726D02*
X810329Y89536D01*
G01X809107Y89030D02*
X808641Y91219D01*
G01X808975Y93093D02*
X809863Y91726D01*
G01X808641Y91219D02*
X808034Y92153D01*
G01X806229Y94876D02*
X808975Y93093D01*
G01X808034Y92153D02*
X808035D01*
G01X816493Y103066D02*
X848108Y96343D01*
G01X816493Y101736D02*
X848085Y95018D01*
G01X817086Y106333D02*
X846919Y99989D01*
G01X817086Y105003D02*
X846911Y98661D01*
G01X849117Y105163D02*
X808376Y113310D01*
G01X808452Y111969D02*
X849117Y103837D01*
G01X806229Y94876D02*
X808975Y93093D01*
G01X808034Y92153D02*
X808035D01*
G01X806229Y94876D02*
X808975Y93093D01*
G01X808641Y91219D02*
X808034Y92153D01*
G01X808975Y93093D02*
X809863Y91726D01*
G01X809107Y89030D02*
X808641Y91219D01*
G01X809863Y91726D02*
X810329Y89536D01*
G01X810027Y87613D02*
X809107Y89030D01*
G01X810329Y89536D02*
X810967Y88553D01*
G01X812451Y86039D02*
X810027Y87613D01*
G01X810967Y88553D02*
X812957Y87261D01*
G01X816720Y85131D02*
X812451Y86039D01*
G01X812957Y87261D02*
X816720Y86461D01*
G01X819525Y85728D02*
X816720Y85131D01*
G01Y86461D02*
X819020Y86950D01*
G01X821342Y86904D02*
X819525Y85728D01*
G01X819020Y86950D02*
X820403Y87845D01*
G01X822681Y88962D02*
X821342Y86904D01*
G01X820403Y87845D02*
X821459Y89468D01*
G01X823386Y92284D02*
X822681Y88962D01*
G01X821459Y89468D02*
X822164Y92790D01*
G01X824219Y93567D02*
X823386Y92284D01*
G01X822164Y92790D02*
X823279Y94507D01*
G01X826791Y95237D02*
X824219Y93567D01*
G01X823279Y94507D02*
X826285Y96459D01*
G01X828492Y95598D02*
X826791Y95237D01*
G01X826285Y96459D02*
X828492Y96928D01*
G01X848365Y91375D02*
X828492Y95598D01*
G01Y96928D02*
X848388Y92700D01*
G01X816493Y101736D02*
X848085Y95018D01*
G01X816493Y103066D02*
X848108Y96343D01*
G01X817086Y105003D02*
X846911Y98661D01*
G01X817086Y106333D02*
X846919Y99989D01*
G01X808452Y111969D02*
X849117Y103837D01*
G01Y105163D02*
X808376Y113310D01*
G01X807976Y117566D02*
X849072Y109346D01*
G01X808052Y116224D02*
X849072Y108020D01*
G01X808052Y116224D02*
X849072Y108020D01*
G01X807976Y117566D02*
X849072Y109346D01*
G01X831295Y124337D02*
X848295Y127333D01*
G01X839683Y127136D02*
X831295Y125658D01*
G01X848069Y128614D02*
X839683Y127136D01*
G01X831295Y125658D02*
X817326Y128120D01*
G01X831295Y125658D02*
X817326Y128120D01*
G01X839683Y127136D02*
X831295Y125658D01*
G01Y124337D02*
X848295Y127333D01*
G01X848069Y128614D02*
X839683Y127136D01*
G01X831295Y124337D02*
X848295Y127333D01*
G01X830131Y121111D02*
X848658Y124380D01*
G01X830131Y119790D02*
X848884Y123099D01*
G01X830131Y119790D02*
X848884Y123099D01*
G01X830131Y121111D02*
X848658Y124380D01*
G01X831881Y140930D02*
X862457Y146320D01*
G01X831881Y139609D02*
X862574Y145020D01*
G01X831881Y139609D02*
X862574Y145020D01*
G01X831881Y140930D02*
X862457Y146320D01*
G01X831699Y129717D02*
X859450Y134608D01*
G01Y133287D02*
X831699Y128396D01*
G01X831650Y133593D02*
X860300Y138642D01*
G01X831650Y132272D02*
X860300Y137321D01*
G01X817525Y136082D02*
X831650Y133593D01*
G01X832900Y137167D02*
X862486Y142383D01*
G01X832900Y135846D02*
X862600Y141083D01*
G01X859450Y133287D02*
X831699Y128396D01*
G01Y129717D02*
X859450Y134608D01*
G01X831650Y132272D02*
X860300Y137321D01*
G01X831650Y133593D02*
X860300Y138642D01*
G01X817525Y136082D02*
X831650Y133593D01*
G01X832900Y135846D02*
X862600Y141083D01*
G01X832900Y137167D02*
X862486Y142383D01*
G01X832746Y156932D02*
X861879Y162068D01*
G01X838850Y156688D02*
X832746Y155611D01*
G01X838850Y156688D02*
X832746Y155611D01*
G01Y156932D02*
X861879Y162068D01*
G01X832746Y156932D02*
X861879Y162068D01*
G01X832746Y156932D02*
X861879Y162068D01*
G01X832887Y145058D02*
X862941Y150350D01*
G01X832888Y143738D02*
X863055Y149050D01*
G01X832888Y143738D02*
X863055Y149050D01*
G01X832887Y145058D02*
X862941Y150350D01*
G01X833548Y149004D02*
X862976Y154194D01*
G01X863100Y152894D02*
X833548Y147683D01*
G01X834200Y152863D02*
X864086Y158131D01*
G01X864200Y156831D02*
X834200Y151542D01*
G01X863100Y152894D02*
X833548Y147683D01*
G01Y149004D02*
X862976Y154194D01*
G01X864200Y156831D02*
X834200Y151542D01*
G01Y152863D02*
X864086Y158131D01*
G01X824110Y193614D02*
X846550Y177903D01*
G01X823176Y192680D02*
X846040Y176672D01*
G01X811274Y211948D02*
X824110Y193614D01*
G01X810340Y211014D02*
X823176Y192680D01*
G01D02*
X846040Y176672D01*
G01X824110Y193614D02*
X846550Y177903D01*
G01X810340Y211014D02*
X823176Y192680D01*
G01X811274Y211948D02*
X824110Y193614D01*
G01X827599Y195591D02*
X814551Y214226D01*
G01X815485Y215160D02*
X828523Y196539D01*
G01X851605Y179678D02*
X827599Y195591D01*
G01X828523Y196539D02*
X852018Y180964D01*
G01X828523Y196539D02*
X852018Y180964D01*
G01X851605Y179678D02*
X827599Y195591D01*
G01X815485Y215160D02*
X828523Y196539D01*
G01X827599Y195591D02*
X814551Y214226D01*
G01X832863Y202848D02*
X846941Y192990D01*
G01X833797Y203782D02*
X847451Y194221D01*
G01X815591Y227515D02*
X832863Y202848D01*
G01X816822Y228025D02*
X833797Y203782D01*
G01X835172Y205575D02*
X849177Y195769D01*
G01X836106Y206509D02*
X849687Y196999D01*
G01X818917Y228793D02*
X835172Y205575D01*
G01X820148Y229303D02*
X836106Y206509D01*
G01X833797Y203782D02*
X847451Y194221D01*
G01X832863Y202848D02*
X846941Y192990D01*
G01X816822Y228025D02*
X833797Y203782D01*
G01X815591Y227515D02*
X832863Y202848D01*
G01X836106Y206509D02*
X849687Y196999D01*
G01X835172Y205575D02*
X849177Y195769D01*
G01X820148Y229303D02*
X836106Y206509D01*
G01X818917Y228793D02*
X835172Y205575D01*
G01X831088Y200062D02*
X812703Y226319D01*
G01X813934Y226829D02*
X832017Y201004D01*
G01X846657Y189480D02*
X831088Y200062D01*
G01X832017Y201004D02*
X847158Y190713D01*
G01X832017Y201004D02*
X847158Y190713D01*
G01X846657Y189480D02*
X831088Y200062D01*
G01X813934Y226829D02*
X832017Y201004D01*
G01X831088Y200062D02*
X812703Y226319D01*
G01X808126Y214152D02*
X811274Y211948D01*
G01X807617Y212921D02*
X810340Y211014D01*
G01X807617Y212921D02*
X810340Y211014D01*
G01X808126Y214152D02*
X811274Y211948D01*
G01X814551Y214226D02*
X809490Y217769D01*
G01X810000Y219000D02*
X815485Y215160D01*
G01X810000Y219000D02*
X815485Y215160D01*
G01X814551Y214226D02*
X809490Y217769D01*
G01X841227Y217127D02*
X823937Y315182D01*
G01X842458Y217637D02*
X825168Y315692D01*
G01X842458Y217637D02*
X825168Y315692D01*
G01X841227Y217127D02*
X823937Y315182D01*
G01X839399Y212803D02*
X821959Y311705D01*
G01X838168Y212293D02*
X820728Y311195D01*
G01X843006Y207652D02*
X839399Y212803D01*
G01X842072Y206718D02*
X838168Y212293D01*
G01X807262Y274750D02*
X815591Y227515D01*
G01X808583Y274750D02*
X816822Y228025D01*
G01X810682Y275500D02*
X818917Y228793D01*
G01X812003Y275500D02*
X820148Y229303D01*
G01X838168Y212293D02*
X820728Y311195D01*
G01X839399Y212803D02*
X821959Y311705D01*
G01X842072Y206718D02*
X838168Y212293D01*
G01X843006Y207652D02*
X839399Y212803D01*
G01X808583Y274750D02*
X816822Y228025D01*
G01X807262Y274750D02*
X815591Y227515D01*
G01X812003Y275500D02*
X820148Y229303D01*
G01X810682Y275500D02*
X818917Y228793D01*
G01X812703Y226319D02*
X808339Y251034D01*
G01X809570Y251544D02*
X813934Y226829D01*
G01X809570Y251544D02*
X813934Y226829D01*
G01X812703Y226319D02*
X808339Y251034D01*
G01X848061Y223995D02*
X831426Y318344D01*
G01X848061Y223995D02*
X831426Y318344D01*
G01X844497Y223648D02*
X827661Y319130D01*
G01X843266Y223138D02*
X826430Y318620D01*
G01X843266Y223138D02*
X826430Y318620D01*
G01X844497Y223648D02*
X827661Y319130D01*
G01X810320Y292092D02*
X807262Y274750D01*
G01X811641Y292092D02*
X808583Y274750D01*
G01X813679Y292500D02*
X810682Y275500D01*
G01X815000Y292500D02*
X812003Y275500D01*
G01X811641Y292092D02*
X808583Y274750D01*
G01X810320Y292092D02*
X807262Y274750D01*
G01X815000Y292500D02*
X812003Y275500D01*
G01X813679Y292500D02*
X810682Y275500D01*
G01X808339Y251034D02*
X806566Y253566D01*
G01X807500Y254500D02*
X809570Y251544D01*
G01X807500Y254500D02*
X809570Y251544D01*
G01X808339Y251034D02*
X806566Y253566D01*
G01X852765Y225787D02*
X836241Y319498D01*
G01X853996Y226297D02*
X837472Y320007D01*
G01X853996Y226297D02*
X837472Y320007D01*
G01X852765Y225787D02*
X836241Y319498D01*
G01X849292Y224505D02*
X832657Y318854D01*
G01X849292Y224505D02*
X832657Y318854D01*
G01X807267Y316900D02*
X811641Y292092D01*
G01X809363Y316976D02*
X813679Y292500D01*
G01X810594Y317486D02*
X815000Y292500D01*
G01X807267Y316900D02*
X811641Y292092D01*
G01X810594Y317486D02*
X815000Y292500D01*
G01X809363Y316976D02*
X813679Y292500D01*
G01X977191Y476610D02*
X813758Y710019D01*
G01X978422Y477120D02*
X814989Y710529D01*
G01X978422Y477120D02*
X814989Y710529D01*
G01X977191Y476610D02*
X813758Y710019D01*
G01X822551Y706365D02*
X810140Y776749D01*
G01X823782Y706875D02*
X811461Y776749D01*
G01X980985Y480095D02*
X822551Y706365D01*
G01X982217Y480604D02*
X823782Y706875D01*
G01X827934Y714652D02*
X821418Y751601D01*
G01X829165Y715161D02*
X822739Y751601D01*
G01X990104Y483048D02*
X827934Y714652D01*
G01X991335Y483558D02*
X829165Y715161D01*
G01X834531Y717472D02*
X994560Y488927D01*
G01X835762Y717981D02*
X995791Y489437D01*
G01X823782Y706875D02*
X811461Y776749D01*
G01X822551Y706365D02*
X810140Y776749D01*
G01X982217Y480604D02*
X823782Y706875D01*
G01X980985Y480095D02*
X822551Y706365D01*
G01X829165Y715161D02*
X822739Y751601D01*
G01X827934Y714652D02*
X821418Y751601D01*
G01X991335Y483558D02*
X829165Y715161D01*
G01X990104Y483048D02*
X827934Y714652D01*
G01X835762Y717981D02*
X995791Y489437D01*
G01X834531Y717472D02*
X994560Y488927D01*
G01X828248Y753101D02*
X834531Y717472D01*
G01X829569Y753101D02*
X835762Y717981D01*
G01X829569Y753101D02*
X835762Y717981D01*
G01X828248Y753101D02*
X834531Y717472D01*
G01X810140Y776749D02*
X816179Y811000D01*
G01X811461Y776749D02*
X817500Y811000D01*
G01X821418Y751601D02*
X832171Y812587D01*
G01X822739Y751601D02*
X833402Y812077D01*
G01X836741Y801262D02*
X828248Y753101D01*
G01X837972Y800752D02*
X829569Y753101D01*
G01X811461Y776749D02*
X817500Y811000D01*
G01X810140Y776749D02*
X816179Y811000D01*
G01X822739Y751601D02*
X833402Y812077D01*
G01X821418Y751601D02*
X832171Y812587D01*
G01X837972Y800752D02*
X829569Y753101D01*
G01X836741Y801262D02*
X828248Y753101D01*
G01X816179Y811000D02*
X813917Y823830D01*
G01X817500Y811000D02*
X815217Y823947D01*
G01X832171Y812587D02*
X839114Y822502D01*
G01X833402Y812077D02*
X840414Y822091D01*
G01X851712Y822642D02*
X836741Y801262D01*
G01X853012Y822231D02*
X837972Y800752D01*
G01X817500Y811000D02*
X815217Y823947D01*
G01X816179Y811000D02*
X813917Y823830D01*
G01X833402Y812077D02*
X840414Y822091D01*
G01X832171Y812587D02*
X839114Y822502D01*
G01X853012Y822231D02*
X837972Y800752D01*
G01X851712Y822642D02*
X836741Y801262D01*
G01X813917Y823830D02*
Y828007D01*
G01X815217Y823947D02*
Y828007D01*
G01X839114Y822502D02*
Y828007D01*
G01X815217Y823947D02*
Y828007D01*
G01X813917Y823830D02*
Y828007D01*
G01X839114Y822502D02*
Y828007D01*
G01X860100Y110226D02*
X874233Y107400D01*
G01X860100Y110226D02*
X874233Y107400D01*
G01X859869Y94721D02*
X880917Y91011D01*
G01Y89690D02*
X859869Y93400D01*
G01X848388Y92700D02*
X859869Y94721D01*
G01Y93400D02*
X848365Y91375D01*
G01X873223Y96128D02*
X878588Y95183D01*
G01X872983Y94850D02*
X878588Y93862D01*
G01X860887Y98596D02*
X873223Y96128D01*
G01X860872Y97273D02*
X872983Y94850D01*
G01X848108Y96343D02*
X860887Y98596D01*
G01X848085Y95018D02*
X860872Y97273D01*
G01X873367Y98700D02*
X877455Y97980D01*
G01X860226Y102652D02*
X873607Y99978D01*
G01X860226Y101326D02*
X873367Y98700D01*
G01X846919Y99989D02*
X860226Y102652D01*
G01X846911Y98661D02*
X860226Y101326D01*
G01X859618Y107263D02*
X849117Y105163D01*
G01Y103837D02*
X859618Y105937D01*
G01X873934Y104400D02*
X859618Y107263D01*
G01Y105937D02*
X873805Y103100D01*
G01X859869Y93400D02*
X848365Y91375D01*
G01X848388Y92700D02*
X859869Y94721D01*
G01X880917Y89690D02*
X859869Y93400D01*
G01Y94721D02*
X880917Y91011D01*
G01X872983Y94850D02*
X878588Y93862D01*
G01X873223Y96128D02*
X878588Y95183D01*
G01X860872Y97273D02*
X872983Y94850D01*
G01X860887Y98596D02*
X873223Y96128D01*
G01X848085Y95018D02*
X860872Y97273D01*
G01X848108Y96343D02*
X860887Y98596D01*
G01X873367Y98700D02*
X877455Y97980D01*
G01X860226Y101326D02*
X873367Y98700D01*
G01X860226Y102652D02*
X873607Y99978D01*
G01X846911Y98661D02*
X860226Y101326D01*
G01X846919Y99989D02*
X860226Y102652D01*
G01X859618Y105937D02*
X873805Y103100D01*
G01X873934Y104400D02*
X859618Y107263D01*
G01X849117Y103837D02*
X859618Y105937D01*
G01Y107263D02*
X849117Y105163D01*
G01X860100Y111552D02*
X874362Y108700D01*
G01X854331Y110398D02*
X860100Y111552D01*
G01X849072Y108020D02*
X860100Y110226D01*
G01X849072Y109346D02*
X854331Y110398D01*
G01X849072Y108020D02*
X860100Y110226D01*
G01Y111552D02*
X874362Y108700D01*
G01X849072Y108020D02*
X860100Y110226D01*
G01X854331Y110398D02*
X860100Y111552D01*
G01X849072Y109346D02*
X854331Y110398D01*
G01X869448Y123814D02*
G03X872572Y122860I4962J10658D01*
G01X872775Y124144D02*
G02X870200Y124901I1637J10327D01*
G01X868570Y124691D02*
X869448Y123814D01*
G01X870200Y124901D02*
X869489Y125611D01*
G01X868569Y124691D02*
X868570D01*
G01X870200Y124901D02*
X869489Y125611D01*
G01X866517Y126743D02*
X868569Y124691D01*
G01X869489Y125611D02*
X867282Y127819D01*
G01X866491Y126761D02*
X866517Y126743D01*
G01X867237Y127827D02*
X864696Y129606D01*
G01X864186Y128375D02*
X866491Y126762D01*
G01X867237Y127827D02*
X864696Y129606D01*
G01X867282Y127819D02*
X867237Y127827D01*
G01X859197Y129254D02*
X864186Y128375D01*
G01X861521Y130165D02*
X859197Y130575D01*
G01X864696Y129606D02*
X861521Y130165D01*
G01X853342Y128223D02*
X859197Y129254D01*
G01X856045Y130020D02*
X853116Y129504D01*
G01X859197Y130575D02*
X856045Y130020D01*
G01X848295Y127333D02*
X853342Y128223D01*
G01X853116Y129504D02*
X848069Y128614D01*
G01X853116Y129504D02*
X848069Y128614D01*
G01X848295Y127333D02*
X853342Y128223D01*
G01X856045Y130020D02*
X853116Y129504D01*
G01X853342Y128223D02*
X859197Y129254D01*
G01Y130575D02*
X856045Y130020D01*
G01X853342Y128223D02*
X859197Y129254D01*
G01X861521Y130165D02*
X859197Y130575D01*
G01Y129254D02*
X864186Y128375D01*
G01X864696Y129606D02*
X861521Y130165D01*
G01X859197Y129254D02*
X864186Y128375D01*
G01X867237Y127827D02*
X864696Y129606D01*
G01X866491Y126761D02*
X866517Y126743D01*
G01X864186Y128375D02*
X866491Y126762D01*
G01X867282Y127819D02*
X867237Y127827D01*
G01X864186Y128375D02*
X866491Y126762D01*
G01X869489Y125611D02*
X867282Y127819D01*
G01X866517Y126743D02*
X868569Y124691D01*
G01X870200Y124901D02*
X869489Y125611D01*
G01X868570Y124691D02*
X869448Y123814D01*
G01X868569Y124691D02*
X868570D01*
G01X872775Y124144D02*
G02X870200Y124901I1637J10327D01*
G01X869448Y123814D02*
G03X872572Y122860I4962J10658D01*
G01X850725Y113605D02*
X847600Y112979D01*
G01X854104Y112954D02*
X847600Y111653D01*
G01X860100Y115479D02*
X850725Y113605D01*
G01X860100Y114153D02*
X854104Y112954D01*
G01X874744Y112550D02*
X860100Y115479D01*
G01X874615Y111250D02*
X860100Y114153D01*
G01X870900Y118760D02*
X871900D01*
G01X870900Y117460D02*
X871900D01*
G01X869734Y119091D02*
G03X870900Y118760I1167J1892D01*
G01X869051Y117983D02*
G03X870900Y117460I1847J3001D01*
G01X869328Y119411D02*
G03X869734Y119091I1570J1574D01*
G01X869051Y117983D02*
G03X870900Y117460I1847J3001D01*
G01X868413Y118487D02*
G03X869051Y117983I2465J2465D01*
G01X865789Y122950D02*
X869328Y119411D01*
G01X864950Y121950D02*
X868413Y118487D01*
G01X863917Y124262D02*
X865789Y122950D01*
G01X863407Y123031D02*
X864950Y121950D01*
G01X861768Y124641D02*
X863917Y124262D01*
G01X855952Y124345D02*
X863407Y123031D01*
G01X858972Y125134D02*
X861768Y124641D01*
G01X855952Y124345D02*
X863407Y123031D01*
G01X856496Y125570D02*
X858972Y125134D01*
G01X855952Y124345D02*
X863407Y123031D01*
G01X855951Y125665D02*
X856496Y125570D01*
G01X855952Y124345D02*
X863407Y123031D01*
G01X848884Y123099D02*
X855952Y124345D01*
G01X852193Y125003D02*
X855951Y125665D01*
G01X848884Y123099D02*
X855952Y124345D01*
G01X848658Y124380D02*
X852193Y125003D01*
G01X848884Y123099D02*
X855952Y124345D01*
G01X854104Y112954D02*
X847600Y111653D01*
G01X850725Y113605D02*
X847600Y112979D01*
G01X860100Y114153D02*
X854104Y112954D01*
G01X860100Y115479D02*
X850725Y113605D01*
G01X874615Y111250D02*
X860100Y114153D01*
G01X874744Y112550D02*
X860100Y115479D01*
G01X870900Y117460D02*
X871900D01*
G01X870900Y118760D02*
X871900D01*
G01X869051Y117983D02*
G03X870900Y117460I1847J3001D01*
G01X869734Y119091D02*
G03X870900Y118760I1167J1892D01*
G01X869328Y119411D02*
G03X869734Y119091I1570J1574D01*
G01X868413Y118487D02*
G03X869051Y117983I2465J2465D01*
G01X869328Y119411D02*
G03X869734Y119091I1570J1574D01*
G01X864950Y121950D02*
X868413Y118487D01*
G01X865789Y122950D02*
X869328Y119411D01*
G01X863407Y123031D02*
X864950Y121950D01*
G01X863917Y124262D02*
X865789Y122950D01*
G01X855952Y124345D02*
X863407Y123031D01*
G01X861768Y124641D02*
X863917Y124262D01*
G01X858972Y125134D02*
X861768Y124641D01*
G01X856496Y125570D02*
X858972Y125134D01*
G01X855951Y125665D02*
X856496Y125570D01*
G01X848884Y123099D02*
X855952Y124345D01*
G01X855951Y125665D02*
X856496Y125570D01*
G01X852193Y125003D02*
X855951Y125665D01*
G01X848658Y124380D02*
X852193Y125003D01*
G01X871000Y134509D02*
X872300D01*
G01Y133209D02*
X871100D01*
G01X870987Y134511D02*
X871000Y134509D01*
G01X871100Y133209D02*
X865501Y132222D01*
G01X872300Y133209D02*
X871100D01*
G01X865501Y133543D02*
X870987Y134511D01*
G01X871100Y133209D02*
X865501Y132222D01*
G01X859450Y134608D02*
X865501Y133543D01*
G01Y132222D02*
X859450Y133287D01*
G01X869586Y138446D02*
X872300D01*
G01X869700Y137146D02*
X872300D01*
G01X865500Y137726D02*
X869586Y138446D01*
G01X865500Y136405D02*
X869700Y137146D01*
G01X862283Y138292D02*
X865500Y137726D01*
G01X860300Y137321D02*
X865500Y136405D01*
G01X860300Y138642D02*
X862283Y138292D01*
G01X860300Y137321D02*
X865500Y136405D01*
G01X862600Y141083D02*
X871203D01*
G01X865501Y132222D02*
X859450Y133287D01*
G01Y134608D02*
X865501Y133543D01*
G01X871100Y133209D02*
X865501Y132222D01*
G01X870987Y134511D02*
X871000Y134509D01*
G01X865501Y133543D02*
X870987Y134511D01*
G01X872300Y133209D02*
X871100D01*
G01X871000Y134509D02*
X872300D01*
G01X870987Y134511D02*
X871000Y134509D01*
G01X869700Y137146D02*
X872300D01*
G01X869586Y138446D02*
X872300D01*
G01X865500Y136405D02*
X869700Y137146D01*
G01X865500Y137726D02*
X869586Y138446D01*
G01X860300Y137321D02*
X865500Y136405D01*
G01X862283Y138292D02*
X865500Y137726D01*
G01X860300Y138642D02*
X862283Y138292D01*
G01X862600Y141083D02*
X871203D01*
G01X865449Y174500D02*
X878350D01*
G01X864599Y175350D02*
X865449Y174500D01*
G01X854403Y175350D02*
X864599D01*
G01X854403D02*
X864599D01*
G01X853319Y175389D02*
X854403Y175350D01*
G01X846040Y176672D02*
X853319Y175389D01*
G01X846040Y176672D02*
X853319Y175389D01*
G01X865449Y174500D02*
X878350D01*
G01X864599Y175350D02*
X865449Y174500D01*
G01X854403Y175350D02*
X864599D01*
G01X853319Y175389D02*
X854403Y175350D01*
G01X846040Y176672D02*
X853319Y175389D01*
G01X862457Y146320D02*
X872100D01*
G01X862574Y145020D02*
X872100D01*
G01X862574D02*
X872100D01*
G01X862457Y146320D02*
X872100D01*
G01X862486Y142383D02*
X871203D01*
G01X862486D02*
X871203D01*
G01X861879Y162068D02*
X872400D01*
G01Y160768D02*
X861993D01*
G01X843479Y157504D02*
X841854Y157217D01*
G01X861993Y160768D02*
X846482Y158033D01*
G01X843479Y157504D02*
X841854Y157217D01*
G01X861993Y160768D02*
X846482Y158033D01*
G01X872400Y160768D02*
X861993D01*
G01X861879Y162068D02*
X872400D01*
G01X862941Y150350D02*
X871606D01*
G01X863055Y149050D02*
X871800D01*
G01X863055D02*
X871800D01*
G01X862941Y150350D02*
X871606D01*
G01X862976Y154194D02*
X872400D01*
G01Y152894D02*
X863100D01*
G01X864086Y158131D02*
X871203D01*
G01Y156831D02*
X864200D01*
G01X872400Y152894D02*
X863100D01*
G01X862976Y154194D02*
X872400D01*
G01X871203Y156831D02*
X864200D01*
G01X864086Y158131D02*
X871203D01*
G01X865988Y175800D02*
X877811D01*
G01X865138Y176650D02*
X865988Y175800D01*
G01X854427Y176650D02*
X865138D01*
G01X853456Y176685D02*
X854427Y176650D01*
G01X846550Y177903D02*
X853456Y176685D01*
G01X865988Y175800D02*
X877811D01*
G01X865138Y176650D02*
X865988Y175800D01*
G01X854427Y176650D02*
X865138D01*
G01X853456Y176685D02*
X854427Y176650D01*
G01X853456Y176685D02*
X854427Y176650D01*
G01X853456Y176685D02*
X854427Y176650D01*
G01X846550Y177903D02*
X853456Y176685D01*
G01X865125Y179184D02*
X851605Y179678D01*
G01X852018Y180964D02*
X865683Y180465D01*
G01X867409Y176900D02*
X865125Y179184D01*
G01X865683Y180465D02*
X867948Y178200D01*
G01X876400Y176900D02*
X867409D01*
G01X867948Y178200D02*
X875861D01*
G01X867948D02*
X875861D01*
G01X876400Y176900D02*
X867409D01*
G01X865683Y180465D02*
X867948Y178200D01*
G01X867409Y176900D02*
X865125Y179184D01*
G01X852018Y180964D02*
X865683Y180465D01*
G01X865125Y179184D02*
X851605Y179678D01*
G01X856921Y208880D02*
X849717Y213925D01*
G01X862486Y207900D02*
X856921Y208880D01*
G01X873000Y207900D02*
X862486D01*
G01X847093Y208749D02*
X841227Y217127D01*
G01X851606Y205589D02*
X847093Y208749D01*
G01X852116Y206820D02*
X848027Y209683D01*
G01X856483Y204729D02*
X851606Y205589D01*
G01X861300Y205200D02*
X852116Y206820D01*
G01X861186Y203900D02*
X856483Y204729D01*
G01X861300Y205200D02*
X852116Y206820D01*
G01X872600Y203900D02*
X861186D01*
G01X872600Y205200D02*
X861300D01*
G01X856921Y208880D02*
X849717Y213925D01*
G01X862486Y207900D02*
X856921Y208880D01*
G01X873000Y207900D02*
X862486D01*
G01X847093Y208749D02*
X841227Y217127D01*
G01X852116Y206820D02*
X848027Y209683D01*
G01X851606Y205589D02*
X847093Y208749D01*
G01X861300Y205200D02*
X852116Y206820D01*
G01X856483Y204729D02*
X851606Y205589D01*
G01X861186Y203900D02*
X856483Y204729D01*
G01X872600Y205200D02*
X861300D01*
G01X872600Y203900D02*
X861186D01*
G01X851873Y201444D02*
X843006Y207652D01*
G01X851363Y200213D02*
X842072Y206718D01*
G01X860108Y199992D02*
X851873Y201444D01*
G01X855766Y199437D02*
X851363Y200213D01*
G01X859994Y198692D02*
X855766Y199437D01*
G01X872553Y199992D02*
X860108D01*
G01X872014Y198692D02*
X859994D01*
G01X874739Y197806D02*
X872553Y199992D01*
G01X873559Y197147D02*
X872014Y198692D01*
G01X870482Y189465D02*
X875666Y188983D01*
G01X870482Y189465D02*
X875666Y188983D01*
G01X870361Y188166D02*
X875720Y187672D01*
G01X870482Y189465D02*
X875666Y188983D01*
G01X870475Y189466D02*
X870482Y189465D01*
G01X858073Y190333D02*
X870361Y188166D01*
G01X870475Y189466D02*
X870482Y189465D01*
G01X858583Y191564D02*
X870475Y189466D01*
G01X856746Y191262D02*
X858073Y190333D01*
G01X857256Y192493D02*
X858583Y191564D01*
G01X846941Y192990D02*
X856746Y191262D01*
G01X856065Y192703D02*
X857256Y192493D01*
G01X856064Y192703D02*
X856065D01*
G01X847451Y194221D02*
X856064Y192703D01*
G01X872272Y191694D02*
X873040Y191830D01*
G01X872272Y193015D02*
X872814Y193111D01*
G01X849687Y196999D02*
X872272Y193015D01*
G01X849177Y195768D02*
X872272Y191694D01*
G01Y193015D02*
X872814Y193111D01*
G01X849687Y196999D02*
X872272Y193015D01*
G01X851363Y200213D02*
X842072Y206718D01*
G01X851873Y201444D02*
X843006Y207652D01*
G01X855766Y199437D02*
X851363Y200213D01*
G01X860108Y199992D02*
X851873Y201444D01*
G01X859994Y198692D02*
X855766Y199437D01*
G01X860108Y199992D02*
X851873Y201444D01*
G01X872014Y198692D02*
X859994D01*
G01X872553Y199992D02*
X860108D01*
G01X873559Y197147D02*
X872014Y198692D01*
G01X874739Y197806D02*
X872553Y199992D01*
G01X870482Y189465D02*
X875666Y188983D01*
G01X870361Y188166D02*
X875720Y187672D01*
G01X870475Y189466D02*
X870482Y189465D01*
G01X870361Y188166D02*
X875720Y187672D01*
G01X858073Y190333D02*
X870361Y188166D01*
G01X858583Y191564D02*
X870475Y189466D01*
G01X858073Y190333D02*
X870361Y188166D01*
G01X857256Y192493D02*
X858583Y191564D01*
G01X856746Y191262D02*
X858073Y190333D01*
G01X856065Y192703D02*
X857256Y192493D01*
G01X846941Y192990D02*
X856746Y191262D01*
G01X856064Y192703D02*
X856065D01*
G01X846941Y192990D02*
X856746Y191262D01*
G01X847451Y194221D02*
X856064Y192703D01*
G01X846941Y192990D02*
X856746Y191262D01*
G01X872272Y193015D02*
X872814Y193111D01*
G01X872272Y191694D02*
X873040Y191830D01*
G01X849177Y195768D02*
X872272Y191694D01*
G01X849687Y196999D02*
X872272Y193015D01*
G01Y191694D02*
X873040Y191830D01*
G01X849177Y195768D02*
X872272Y191694D01*
G01X854394Y188116D02*
X846660Y189480D01*
G01X847158Y190713D02*
X854904Y189347D01*
G01X858429Y185292D02*
X854394Y188116D01*
G01X854904Y189347D02*
X858939Y186523D01*
G01X862660Y184545D02*
X858429Y185292D01*
G01X858939Y186523D02*
X863170Y185776D01*
G01X869322Y179880D02*
X862660Y184545D01*
G01X869831Y181112D02*
X869854Y181108D01*
G01X863170Y185776D02*
X869831Y181112D01*
G01X869741Y179808D02*
X869322Y179880D01*
G01X869854Y181108D02*
X871437D01*
G01X869831Y181112D02*
X869854Y181108D01*
G01X871437Y179808D02*
X869741D01*
G01X869854Y181108D02*
X871437D01*
G01X869854D02*
X871437D01*
G01X869741Y179808D02*
X869322Y179880D01*
G01X871437Y179808D02*
X869741D01*
G01X869831Y181112D02*
X869854Y181108D01*
G01X869322Y179880D02*
X862660Y184545D01*
G01X869741Y179808D02*
X869322Y179880D01*
G01X863170Y185776D02*
X869831Y181112D01*
G01X869322Y179880D02*
X862660Y184545D01*
G01X858939Y186523D02*
X863170Y185776D01*
G01X862660Y184545D02*
X858429Y185292D01*
G01X854904Y189347D02*
X858939Y186523D01*
G01X858429Y185292D02*
X854394Y188116D01*
G01X847158Y190713D02*
X854904Y189347D01*
G01X854394Y188116D02*
X846660Y189480D01*
G01X868956Y223700D02*
X873300D01*
G01X869070Y225000D02*
X873300D01*
G01X866695Y224098D02*
X868956Y223700D01*
G01X867205Y225329D02*
X869070Y225000D01*
G01X862127Y227297D02*
X866695Y224098D01*
G01X863061Y228231D02*
X867205Y225329D01*
G01X860109Y230178D02*
X862127Y227297D01*
G01X861340Y230688D02*
X863061Y228231D01*
G01X858079Y241680D02*
X860109Y230178D01*
G01X860945Y232926D02*
X861340Y230688D01*
G01X860115Y237634D02*
X860402Y236009D01*
G01X859362Y241907D02*
X859572Y240716D01*
G01X856623Y249934D02*
X858079Y241680D01*
G01X858742Y245424D02*
X859362Y241907D01*
G01X871036Y227700D02*
X872700D01*
G01X871150Y229000D02*
X872600D01*
G01X869183Y228026D02*
X871036Y227700D01*
G01X869693Y229257D02*
X871150Y229000D01*
G01X867207Y229410D02*
X869183Y228026D01*
G01X868140Y230344D02*
X869693Y229257D01*
G01X865098Y232420D02*
X867207Y229410D01*
G01X866329Y232930D02*
X868140Y230344D01*
G01X862145Y249165D02*
X865098Y232420D01*
G01X865630Y236894D02*
X866329Y232930D01*
G01X864800Y241601D02*
X865087Y239976D01*
G01X870633Y235545D02*
X872006Y233585D01*
G01X871864Y236055D02*
X873439Y233806D01*
G01X869050Y244519D02*
X870633Y235545D01*
G01X870332Y244745D02*
X871864Y236055D01*
G01X869070Y225000D02*
X873300D01*
G01X868956Y223700D02*
X873300D01*
G01X867205Y225329D02*
X869070Y225000D01*
G01X866695Y224098D02*
X868956Y223700D01*
G01X863061Y228231D02*
X867205Y225329D01*
G01X862127Y227297D02*
X866695Y224098D01*
G01X861340Y230688D02*
X863061Y228231D01*
G01X860109Y230178D02*
X862127Y227297D01*
G01X860945Y232926D02*
X861340Y230688D01*
G01X858079Y241680D02*
X860109Y230178D01*
G01X860115Y237634D02*
X860402Y236009D01*
G01X858079Y241680D02*
X860109Y230178D01*
G01X859362Y241907D02*
X859572Y240716D01*
G01X858079Y241680D02*
X860109Y230178D01*
G01X858742Y245424D02*
X859362Y241907D01*
G01X856623Y249934D02*
X858079Y241680D01*
G01X856623Y249934D02*
X858079Y241680D01*
G01X871150Y229000D02*
X872600D01*
G01X871036Y227700D02*
X872700D01*
G01X869693Y229257D02*
X871150Y229000D01*
G01X869183Y228026D02*
X871036Y227700D01*
G01X868140Y230344D02*
X869693Y229257D01*
G01X867207Y229410D02*
X869183Y228026D01*
G01X866329Y232930D02*
X868140Y230344D01*
G01X865098Y232420D02*
X867207Y229410D01*
G01X865630Y236894D02*
X866329Y232930D01*
G01X862145Y249165D02*
X865098Y232420D01*
G01X864800Y241601D02*
X865087Y239976D01*
G01X862145Y249165D02*
X865098Y232420D01*
G01X862145Y249165D02*
X865098Y232420D01*
G01X862145Y249165D02*
X865098Y232420D01*
G01X871864Y236055D02*
X873439Y233806D01*
G01X870633Y235545D02*
X872006Y233585D01*
G01X870332Y244745D02*
X871864Y236055D01*
G01X869050Y244519D02*
X870633Y235545D01*
G01X866393Y221100D02*
X873100D01*
G01X866279Y219800D02*
X873100D01*
G01X864803Y221380D02*
X866393Y221100D01*
G01X864293Y220149D02*
X866279Y219800D01*
G01X860852Y224146D02*
X864803Y221380D01*
G01X859918Y223212D02*
X864293Y220149D01*
G01X857586Y228810D02*
X860852Y224146D01*
G01X856355Y228300D02*
X859918Y223212D01*
G01X841280Y321285D02*
X857586Y228810D01*
G01X840049Y320775D02*
X856355Y228300D01*
G01X857043Y219678D02*
X852765Y225787D01*
G01X857977Y220612D02*
X853996Y226297D01*
G01X861667Y216440D02*
X857043Y219678D01*
G01X862177Y217671D02*
X857977Y220612D01*
G01X864733Y215900D02*
X861667Y216440D01*
G01X864847Y217200D02*
X862177Y217671D01*
G01X873100Y215900D02*
X864733D01*
G01X873100Y217200D02*
X864847D01*
G01X866279Y219800D02*
X873100D01*
G01X866393Y221100D02*
X873100D01*
G01X864293Y220149D02*
X866279Y219800D01*
G01X864803Y221380D02*
X866393Y221100D01*
G01X859918Y223212D02*
X864293Y220149D01*
G01X860852Y224146D02*
X864803Y221380D01*
G01X856355Y228300D02*
X859918Y223212D01*
G01X857586Y228810D02*
X860852Y224146D01*
G01X840049Y320775D02*
X856355Y228300D01*
G01X841280Y321285D02*
X857586Y228810D01*
G01X857977Y220612D02*
X853996Y226297D01*
G01X857043Y219678D02*
X852765Y225787D01*
G01X862177Y217671D02*
X857977Y220612D01*
G01X861667Y216440D02*
X857043Y219678D01*
G01X864847Y217200D02*
X862177Y217671D01*
G01X864733Y215900D02*
X861667Y216440D01*
G01X873100Y217200D02*
X864847D01*
G01X873100Y215900D02*
X864733D01*
G01X852789Y217243D02*
X848061Y223995D01*
G01X853723Y218177D02*
X849292Y224505D01*
G01X859220Y212740D02*
X852789Y217243D01*
G01X859730Y213971D02*
X853723Y218177D01*
G01X863986Y211900D02*
X859220Y212740D01*
G01X864100Y213200D02*
X859730Y213971D01*
G01X873200Y211900D02*
X863986D01*
G01X873200Y213200D02*
X864100D01*
G01X853723Y218177D02*
X849292Y224505D01*
G01X852789Y217243D02*
X848061Y223995D01*
G01X859730Y213971D02*
X853723Y218177D01*
G01X859220Y212740D02*
X852789Y217243D01*
G01X864100Y213200D02*
X859730Y213971D01*
G01X863986Y211900D02*
X859220Y212740D01*
G01X873200Y213200D02*
X864100D01*
G01X873200Y211900D02*
X863986D01*
G01X850651Y214859D02*
X844497Y223648D01*
G01X849717Y213925D02*
X843266Y223138D01*
G01X857431Y210111D02*
X850651Y214859D01*
G01X862600Y209200D02*
X857431Y210111D01*
G01X873000Y209200D02*
X862600D01*
G01X848027Y209683D02*
X842458Y217637D01*
G01X849717Y213925D02*
X843266Y223138D01*
G01X850651Y214859D02*
X844497Y223648D01*
G01X857431Y210111D02*
X850651Y214859D01*
G01X862600Y209200D02*
X857431Y210111D01*
G01X873000Y209200D02*
X862600D01*
G01X848027Y209683D02*
X842458Y217637D01*
G01X873393Y270944D02*
X876813Y266062D01*
G01X858758Y353947D02*
X873393Y270944D01*
G01D02*
X876813Y266062D01*
G01X858758Y353947D02*
X873393Y270944D01*
G01X873463Y259734D02*
G03X874311Y259527I848J1632D01*
G01X872738Y260199D02*
G03X873382Y259775I2348J2866D01*
G01X873388Y261364D02*
G03X873563Y261205I1702J1698D01*
G01X872468Y260444D02*
G03X872738Y260199I2622J2618D01*
G01X873388Y261364D02*
G03X873563Y261205I1702J1698D01*
G01X870070Y262842D02*
X872468Y260444D01*
G01X871526Y263226D02*
X873388Y261364D01*
G01X854184Y351549D02*
X869461Y264930D01*
G01X870626Y265811D02*
X870736Y265194D01*
G01X857609Y339620D02*
X870627Y265811D01*
G01X873463Y259734D02*
G03X874311Y259527I848J1632D01*
G01X873463Y259734D02*
G03X874311Y259527I848J1632D01*
G01X872738Y260199D02*
G03X873382Y259775I2348J2866D01*
G01X872468Y260444D02*
G03X872738Y260199I2622J2618D01*
G01X873388Y261364D02*
G03X873563Y261205I1702J1698D01*
G01X872738Y260199D02*
G03X873382Y259775I2348J2866D01*
G01X872468Y260444D02*
G03X872738Y260199I2622J2618D01*
G01X871526Y263226D02*
X873388Y261364D01*
G01X870070Y262842D02*
X872468Y260444D01*
G01X870626Y265811D02*
X870736Y265194D01*
G01X854184Y351549D02*
X869461Y264930D01*
G01X857609Y339620D02*
X870627Y265811D01*
G01X854184Y351549D02*
X869461Y264930D01*
G01X854184Y351549D02*
X869461Y264930D01*
G01X857907Y250161D02*
X858742Y245424D01*
G01X855882Y254141D02*
X856623Y249934D01*
G01X857297Y253618D02*
X857907Y250161D01*
G01X857165Y254368D02*
X857297Y253618D01*
G01X854128Y264092D02*
X855882Y254141D01*
G01X857165Y254368D02*
X857297Y253618D01*
G01X856533Y257950D02*
X857165Y254368D01*
G01X855410Y264319D02*
X856533Y257950D01*
G01X848445Y296322D02*
X854128Y264092D01*
G01X853065Y277617D02*
X855410Y264319D01*
G01X864036Y245934D02*
X864256Y244684D01*
G01X863426Y249391D02*
X864036Y245934D01*
G01X858751Y268412D02*
X862145Y249165D01*
G01X860032Y268638D02*
X863426Y249391D01*
G01X853117Y300362D02*
X858751Y268412D01*
G01X857750Y281585D02*
X860032Y268638D01*
G01X863272Y277289D02*
X869050Y244519D01*
G01X869686Y248404D02*
X870332Y244745D01*
G01X869400Y250029D02*
X869686Y248404D01*
G01X868570Y254737D02*
X868856Y253112D01*
G01X864553Y277515D02*
X868026Y257819D01*
G01X857907Y250161D02*
X858742Y245424D01*
G01X857297Y253618D02*
X857907Y250161D01*
G01X855882Y254141D02*
X856623Y249934D01*
G01X857165Y254368D02*
X857297Y253618D01*
G01X855882Y254141D02*
X856623Y249934D01*
G01X854128Y264092D02*
X855882Y254141D01*
G01X856533Y257950D02*
X857165Y254368D01*
G01X854128Y264092D02*
X855882Y254141D01*
G01X855410Y264319D02*
X856533Y257950D01*
G01X854128Y264092D02*
X855882Y254141D01*
G01X853065Y277617D02*
X855410Y264319D01*
G01X848445Y296322D02*
X854128Y264092D01*
G01X848445Y296322D02*
X854128Y264092D01*
G01X864036Y245934D02*
X864256Y244684D01*
G01X863426Y249391D02*
X864036Y245934D01*
G01X860032Y268638D02*
X863426Y249391D01*
G01X858751Y268412D02*
X862145Y249165D01*
G01X857750Y281585D02*
X860032Y268638D01*
G01X853117Y300362D02*
X858751Y268412D01*
G01X853117Y300362D02*
X858751Y268412D01*
G01X869686Y248404D02*
X870332Y244745D01*
G01X863272Y277289D02*
X869050Y244519D01*
G01X869400Y250029D02*
X869686Y248404D01*
G01X863272Y277289D02*
X869050Y244519D01*
G01X868570Y254737D02*
X868856Y253112D01*
G01X863272Y277289D02*
X869050Y244519D01*
G01X864553Y277515D02*
X868026Y257819D01*
G01X863272Y277289D02*
X869050Y244519D01*
G01X859989Y354457D02*
X874624Y271454D01*
G01X859989Y354457D02*
X874624Y271454D01*
G01X849727Y296549D02*
X853065Y277617D01*
G01X843446Y324674D02*
X848445Y296322D01*
G01X847389Y309810D02*
X849727Y296549D01*
G01X844677Y325184D02*
X847389Y309810D01*
G01X854399Y300588D02*
X857750Y281585D01*
G01X848977Y323845D02*
X853117Y300362D01*
G01X852073Y313778D02*
X854399Y300588D01*
G01X851219Y345643D02*
X863272Y277289D01*
G01X856673Y322206D02*
X864553Y277515D01*
G01X849727Y296549D02*
X853065Y277617D01*
G01X847389Y309810D02*
X849727Y296549D01*
G01X843446Y324674D02*
X848445Y296322D01*
G01X844677Y325184D02*
X847389Y309810D01*
G01X843446Y324674D02*
X848445Y296322D01*
G01X854399Y300588D02*
X857750Y281585D01*
G01X852073Y313778D02*
X854399Y300588D01*
G01X848977Y323845D02*
X853117Y300362D01*
G01X848977Y323845D02*
X853117Y300362D01*
G01X856673Y322206D02*
X864553Y277515D01*
G01X851219Y345643D02*
X863272Y277289D01*
G01X851219Y345643D02*
X863272Y277289D01*
G01X883600Y270967D02*
X870138Y347336D01*
G01X871369Y347846D02*
X884881Y271192D01*
G01X883600Y270967D02*
X870138Y347336D01*
G01X871369Y347846D02*
X884881Y271192D01*
G01X883600Y270967D02*
X870138Y347336D01*
G01X855415Y352059D02*
X857609Y339620D01*
G01X855415Y352059D02*
X857609Y339620D01*
G01X850208Y324355D02*
X852073Y313778D01*
G01X852450Y346153D02*
X856673Y322206D01*
G01X850208Y324355D02*
X852073Y313778D01*
G01X852450Y346153D02*
X856673Y322206D01*
G01X840414Y822091D02*
Y828007D01*
G01X851712D02*
Y822642D01*
G01X853012Y828007D02*
Y822231D01*
G01X840414Y822091D02*
Y828007D01*
G01X853012D02*
Y822231D01*
G01X851712Y828007D02*
Y822642D01*
G01X878003Y107400D02*
G03X881244Y108742I0J4585D01*
G01X874233Y107400D02*
X878003D01*
G01D02*
G03X881244Y108742I0J4585D01*
G01X874233Y107400D02*
X878003D01*
G01X899326Y105571D02*
Y112428D01*
G01X900626D02*
Y105457D01*
G01X899084Y104196D02*
X899326Y105571D01*
G01X900626Y105457D02*
X900315Y103686D01*
G01X897652Y102153D02*
X899084Y104196D01*
G01X900315Y103686D02*
X898652Y101313D01*
G01X887709Y92210D02*
X897652Y102153D01*
G01X898652Y101313D02*
X888339Y91000D01*
G01X880917Y91011D02*
X887709Y92210D01*
G01X888339Y91000D02*
X880917Y89690D01*
G01X892250Y104750D02*
X895124Y108854D01*
G01X893250Y103911D02*
X896355Y108344D01*
G01X890850Y103350D02*
X892250Y104750D01*
G01X891689Y102350D02*
X893250Y103911D01*
G01X887086Y100714D02*
X890850Y103350D01*
G01X888020Y99780D02*
X891689Y102350D01*
G01X884450Y96950D02*
X887086Y100714D01*
G01X885450Y96111D02*
X888020Y99780D01*
G01X883650Y96150D02*
X884450Y96950D01*
G01X884189Y94850D02*
X885450Y96111D01*
G01X883559Y96060D02*
X883647Y96148D01*
G01X884189Y94850D02*
X885450Y96111D01*
G01X878588Y95183D02*
X883559Y96060D01*
G01X878588Y93862D02*
X884189Y94850D01*
G01X888970Y106728D02*
X891451Y110323D01*
G01X889907Y105797D02*
X892751Y109917D01*
G01X884830Y103830D02*
X888970Y106728D01*
G01X885669Y102830D02*
X889907Y105797D01*
G01X880911Y99911D02*
X884830Y103830D01*
G01X881540Y98700D02*
X885669Y102830D01*
G01X877452Y99301D02*
X880911Y99911D01*
G01X877455Y97980D02*
X881540Y98700D01*
G01X873607Y99978D02*
X877452Y99301D01*
G01X879531Y104400D02*
X873934D01*
G01X873805Y103100D02*
X879941D01*
G01X885999Y108930D02*
X879531Y104400D01*
G01X879941Y103100D02*
X886933Y107996D01*
G01D02*
X888703Y110524D01*
G01X888339Y91000D02*
X880917Y89690D01*
G01Y91011D02*
X887709Y92210D01*
G01X898652Y101313D02*
X888339Y91000D01*
G01X887709Y92210D02*
X897652Y102153D01*
G01X900315Y103686D02*
X898652Y101313D01*
G01X897652Y102153D02*
X899084Y104196D01*
G01X900626Y105457D02*
X900315Y103686D01*
G01X899084Y104196D02*
X899326Y105571D01*
G01X900626Y112428D02*
Y105457D01*
G01X899326Y105571D02*
Y112428D01*
G01X893250Y103911D02*
X896355Y108344D01*
G01X892250Y104750D02*
X895124Y108854D01*
G01X891689Y102350D02*
X893250Y103911D01*
G01X890850Y103350D02*
X892250Y104750D01*
G01X888020Y99780D02*
X891689Y102350D01*
G01X887086Y100714D02*
X890850Y103350D01*
G01X885450Y96111D02*
X888020Y99780D01*
G01X884450Y96950D02*
X887086Y100714D01*
G01X884189Y94850D02*
X885450Y96111D01*
G01X883650Y96150D02*
X884450Y96950D01*
G01X883559Y96060D02*
X883647Y96148D01*
G01X878588Y93862D02*
X884189Y94850D01*
G01X878588Y95183D02*
X883559Y96060D01*
G01X889907Y105797D02*
X892751Y109917D01*
G01X888970Y106728D02*
X891451Y110323D01*
G01X885669Y102830D02*
X889907Y105797D01*
G01X884830Y103830D02*
X888970Y106728D01*
G01X881540Y98700D02*
X885669Y102830D01*
G01X880911Y99911D02*
X884830Y103830D01*
G01X877455Y97980D02*
X881540Y98700D01*
G01X877452Y99301D02*
X880911Y99911D01*
G01X873607Y99978D02*
X877452Y99301D01*
G01X886933Y107996D02*
X888703Y110524D01*
G01X879941Y103100D02*
X886933Y107996D01*
G01X885999Y108930D02*
X879531Y104400D01*
G01X873805Y103100D02*
X879941D01*
G01X879531Y104400D02*
X873934D01*
G01X883080Y116265D02*
G02X883485Y117544I2221J0D01*
G01X884548Y116795D02*
G02X886221Y116265I753J-530D01*
G01X884380D02*
G02X884548Y116795I920J0D01*
G01X883080Y113600D02*
Y116265D01*
G01X884380Y113593D02*
Y116265D01*
G01X882985Y112869D02*
G03X883080Y113600I-2756J730D01*
G01X884242Y112535D02*
G03X884380Y113593I-3987J1058D01*
G01X883165Y110664D02*
G03X884242Y112535I-2936J2936D01*
G01X882245Y111584D02*
G03X882985Y112869I-2016J2016D01*
G01X883165Y110664D02*
G03X884242Y112535I-2936J2936D01*
G01X880324Y109662D02*
X882245Y111584D01*
G01X881244Y108742D02*
X883165Y110664D01*
G01X878002Y108700D02*
G03X880324Y109662I0J3284D01*
G01X874362Y108700D02*
X878002D01*
G01X884548Y116795D02*
G02X886221Y116265I753J-530D01*
G01X883080D02*
G02X883485Y117544I2221J0D01*
G01X884380Y116265D02*
G02X884548Y116795I920J0D01*
G01X883080Y116265D02*
G02X883485Y117544I2221J0D01*
G01X884380Y113593D02*
Y116265D01*
G01X883080Y113600D02*
Y116265D01*
G01X884242Y112535D02*
G03X884380Y113593I-3987J1058D01*
G01X882985Y112869D02*
G03X883080Y113600I-2756J730D01*
G01X883165Y110664D02*
G03X884242Y112535I-2936J2936D01*
G01X882985Y112869D02*
G03X883080Y113600I-2756J730D01*
G01X882245Y111584D02*
G03X882985Y112869I-2016J2016D01*
G01X881244Y108742D02*
X883165Y110664D01*
G01X880324Y109662D02*
X882245Y111584D01*
G01X878002Y108700D02*
G03X880324Y109662I0J3284D01*
G01X874362Y108700D02*
X878002D01*
G01X895414Y110500D02*
Y112867D01*
G01X896714Y110386D02*
Y112867D01*
G01X895124Y108854D02*
X895414Y110500D01*
G01X896355Y108344D02*
X896714Y110386D01*
G01X891451Y110323D02*
Y113905D01*
G01X892751Y109917D02*
Y113905D01*
G01X887472Y111034D02*
X885999Y108930D01*
G01X887540Y111415D02*
X887472Y111034D01*
G01X888703Y110524D02*
X888840Y111301D01*
G01X887540Y114900D02*
Y111415D01*
G01X888840Y111301D02*
Y114900D01*
G01X896714Y110386D02*
Y112867D01*
G01X895414Y110500D02*
Y112867D01*
G01X896355Y108344D02*
X896714Y110386D01*
G01X895124Y108854D02*
X895414Y110500D01*
G01X892751Y109917D02*
Y113905D01*
G01X891451Y110323D02*
Y113905D01*
G01X888840Y111301D02*
Y114900D01*
G01X887540D02*
Y111415D01*
G01X888703Y110524D02*
X888840Y111301D01*
G01X887540Y111415D02*
X887472Y111034D01*
G01D02*
X885999Y108930D01*
G01X878657Y112550D02*
X874744D01*
G01X879196Y111250D02*
X874615D01*
G01X879657Y113550D02*
X878657Y112550D01*
G01X880957Y113011D02*
X879196Y111250D01*
G01X879657Y114100D02*
Y113550D01*
G01X880957Y114100D02*
Y113011D01*
G01X879196Y111250D02*
X874615D01*
G01X878657Y112550D02*
X874744D01*
G01X880957Y113011D02*
X879196Y111250D01*
G01X879657Y113550D02*
X878657Y112550D01*
G01X880957Y114100D02*
Y113011D01*
G01X879657Y114100D02*
Y113550D01*
G01X880197Y175350D02*
X881381Y176534D01*
G01X880197Y175350D02*
X881381Y176534D01*
G01X879200Y175350D02*
X880197D01*
G01X878350Y174500D02*
X879200Y175350D01*
G01X880197D02*
X881381Y176534D01*
G01X879200Y175350D02*
X880197D01*
G01X878350Y174500D02*
X879200Y175350D01*
G01X880842Y177834D02*
X882872D01*
G01X881381Y176534D02*
X882872D01*
G01X879658Y176650D02*
X880842Y177834D01*
G01X881381Y176534D02*
X882872D01*
G01X878661Y176650D02*
X879658D01*
G01X877811Y175800D02*
X878661Y176650D01*
G01X881381Y176534D02*
X882872D01*
G01X880842Y177834D02*
X882872D01*
G01X879658Y176650D02*
X880842Y177834D01*
G01X879658Y176650D02*
X880842Y177834D01*
G01X878661Y176650D02*
X879658D01*
G01X878661D02*
X879658D01*
G01X877811Y175800D02*
X878661Y176650D01*
G01X877600Y178100D02*
X876400Y176900D01*
G01X875861Y178200D02*
X876900Y179239D01*
G01X878732Y178100D02*
X877600D01*
G01X877289Y179400D02*
X878172D01*
G01X886269Y185430D02*
X879085Y178246D01*
G01X878561Y179561D02*
X885350Y186350D01*
G01X889576Y186800D02*
G03X886269Y185430I0J-4677D01*
G01X885350Y186350D02*
G02X889575Y188100I4226J-4227D01*
G01X942693Y186800D02*
X889576D01*
G01X889575Y188100D02*
X942693D01*
G01X889575D02*
X942693D01*
G01Y186800D02*
X889576D01*
G01X885350Y186350D02*
G02X889575Y188100I4226J-4227D01*
G01X889576Y186800D02*
G03X886269Y185430I0J-4677D01*
G01X878561Y179561D02*
X885350Y186350D01*
G01X886269Y185430D02*
X879085Y178246D01*
G01X877289Y179400D02*
X878172D01*
G01X878732Y178100D02*
X877600D01*
G01X875861Y178200D02*
X876900Y179239D01*
G01X877600Y178100D02*
X876400Y176900D01*
G01X875891Y187702D02*
X876433Y187797D01*
G01X875720Y187672D02*
X875891Y187702D01*
G01D02*
X876433Y187797D01*
G01X875720Y187672D02*
X875891Y187702D01*
G01X899300Y269646D02*
Y263600D01*
G01X900600Y269516D02*
Y263600D01*
G01X902386Y285076D02*
X899300Y269646D01*
G01X903709Y285061D02*
X900600Y269516D01*
G01X903300Y269248D02*
Y263700D01*
G01X904600Y269118D02*
Y263700D01*
G01X906778Y286637D02*
X903300Y269248D01*
G01X908101Y286622D02*
X904600Y269118D01*
G01X900600Y269516D02*
Y263600D01*
G01X899300Y269646D02*
Y263600D01*
G01X903709Y285061D02*
X900600Y269516D01*
G01X902386Y285076D02*
X899300Y269646D01*
G01X904600Y269118D02*
Y263700D01*
G01X903300Y269248D02*
Y263700D01*
G01X908101Y286622D02*
X904600Y269118D01*
G01X906778Y286637D02*
X903300Y269248D01*
G01X895400Y270035D02*
Y263600D01*
G01X896700Y269902D02*
Y263894D01*
G01X898418Y285125D02*
X895400Y270035D01*
G01X899718Y284994D02*
X896700Y269902D01*
G01D02*
Y263894D01*
G01X895400Y270035D02*
Y263600D01*
G01X899718Y284994D02*
X896700Y269902D01*
G01X898418Y285125D02*
X895400Y270035D01*
G01X891500Y270422D02*
X894743Y286637D01*
G01X896066Y286622D02*
X892800Y270292D01*
G01X891500Y263700D02*
Y270422D01*
G01X892800Y270292D02*
Y263700D01*
G01Y270292D02*
Y263700D01*
G01X891500D02*
Y270422D01*
G01X896066Y286622D02*
X892800Y270292D01*
G01X891500Y270422D02*
X894743Y286637D01*
G01X884881Y271192D02*
X884900Y271081D01*
G01X883600Y263700D02*
Y270967D01*
G01X884900Y271081D02*
Y263700D01*
G01X887646Y270806D02*
Y263900D01*
G01X888946D02*
Y270676D01*
G01X890497Y285061D02*
X887646Y270806D01*
G01X888946Y270676D02*
X891823Y285061D01*
G01X884900Y271081D02*
Y263700D01*
G01X883600D02*
Y270967D01*
G01X884881Y271192D02*
X884900Y271081D01*
G01X888946Y270676D02*
X891823Y285061D01*
G01X890497D02*
X887646Y270806D01*
G01X888946Y263900D02*
Y270676D01*
G01X887646Y270806D02*
Y263900D01*
G01X874624Y271454D02*
X877784Y266942D01*
G01X874624Y271454D02*
X877784Y266942D01*
G01X874311Y259527D02*
G02X874368Y259526I-3J-1797D01*
G01X874311Y260827D02*
G02X876501Y259920I0J-3097D01*
G01X874311Y260827D02*
G02X876501Y259920I0J-3097D01*
G01X874062Y260888D02*
G03X874311Y260827I249J478D01*
G01X873563Y261205D02*
G03X873981Y260930I1523J1860D01*
G01X873563Y261205D02*
G03X873981Y260930I1523J1860D01*
G01X874311Y260827D02*
G02X876501Y259920I0J-3097D01*
G01X874311Y259527D02*
G02X874368Y259526I-3J-1797D01*
G01X874062Y260888D02*
G03X874311Y260827I249J478D01*
G01X873563Y261205D02*
G03X873981Y260930I1523J1860D01*
G01X889104Y360397D02*
X902386Y285076D01*
G01X890335Y360907D02*
X903709Y285061D01*
G01X893252Y363340D02*
X906778Y286637D01*
G01X894483Y363850D02*
X908101Y286622D01*
G01X890335Y360907D02*
X903709Y285061D01*
G01X889104Y360397D02*
X902386Y285076D01*
G01X894483Y363850D02*
X908101Y286622D01*
G01X893252Y363340D02*
X906778Y286637D01*
G01X898418Y286810D02*
Y285125D01*
G01X899718Y286924D02*
Y284994D01*
G01X886700Y353259D02*
X898418Y286810D01*
G01X887931Y353769D02*
X899718Y286924D01*
G01D02*
Y284994D01*
G01X898418Y286810D02*
Y285125D01*
G01X887931Y353769D02*
X899718Y286924D01*
G01X886700Y353259D02*
X898418Y286810D01*
G01X894743Y286637D02*
X883864Y348329D01*
G01X885095Y348839D02*
X896066Y286622D01*
G01X885095Y348839D02*
X896066Y286622D01*
G01X894743Y286637D02*
X883864Y348329D01*
G01X878541Y344838D02*
X890497Y285061D01*
G01X891823D02*
X879763Y345361D01*
G01X891823Y285061D02*
X879763Y345361D01*
G01X878541Y344838D02*
X890497Y285061D01*
G01X934800Y277202D02*
Y263800D01*
G01X936100Y277073D02*
Y263800D01*
G01X938700D02*
Y276814D01*
G01X940000Y263800D02*
Y276684D01*
G01X936100Y277073D02*
Y263800D01*
G01X934800Y277202D02*
Y263800D01*
G01X940000D02*
Y276684D01*
G01X938700Y263800D02*
Y276814D01*
G01X932100Y263800D02*
Y277471D01*
G01X930800Y263800D02*
Y277600D01*
G01X926800Y277998D02*
Y263700D01*
G01X928100Y277869D02*
Y263700D01*
G01X930800Y263800D02*
Y277600D01*
G01X932100Y263800D02*
Y277471D01*
G01X928100Y277869D02*
Y263700D01*
G01X926800Y277998D02*
Y263700D01*
G01X922900D02*
Y278387D01*
G01X924200Y263700D02*
Y278257D01*
G01Y263700D02*
Y278257D01*
G01X922900Y263700D02*
Y278387D01*
G01X919000Y263700D02*
Y278775D01*
G01X920300Y263700D02*
Y278645D01*
G01Y263700D02*
Y278645D01*
G01X919000Y263700D02*
Y278775D01*
G01X915100Y279163D02*
Y263800D01*
G01X916400Y279033D02*
Y263800D01*
G01Y279033D02*
Y263800D01*
G01X915100Y279163D02*
Y263800D01*
G01X911100Y263700D02*
Y279561D01*
G01X912400Y263700D02*
Y279431D01*
G01Y263700D02*
Y279431D01*
G01X911100Y263700D02*
Y279561D01*
G01X937772Y292061D02*
X934800Y277202D01*
G01X939098Y292061D02*
X936100Y277073D01*
G01X935272Y304561D02*
X937772Y292061D01*
G01X936598Y304561D02*
X939098Y292061D01*
G01X937772Y317061D02*
X935272Y304561D01*
G01X939098Y317061D02*
X936598Y304561D01*
G01X939249D02*
X941749Y317061D01*
G01X940575Y304561D02*
X943075Y317061D01*
G01X941749Y292061D02*
X939249Y304561D01*
G01X943075Y292061D02*
X940575Y304561D01*
G01X938700Y276814D02*
X941749Y292061D01*
G01X940000Y276684D02*
X943075Y292061D01*
G01X939098D02*
X936100Y277073D01*
G01X937772Y292061D02*
X934800Y277202D01*
G01X936598Y304561D02*
X939098Y292061D01*
G01X935272Y304561D02*
X937772Y292061D01*
G01X939098Y317061D02*
X936598Y304561D01*
G01X937772Y317061D02*
X935272Y304561D01*
G01X940575D02*
X943075Y317061D01*
G01X939249Y304561D02*
X941749Y317061D01*
G01X943075Y292061D02*
X940575Y304561D01*
G01X941749Y292061D02*
X939249Y304561D01*
G01X940000Y276684D02*
X943075Y292061D01*
G01X938700Y276814D02*
X941749Y292061D01*
G01X932518Y304561D02*
X935018Y317061D01*
G01X931192Y304561D02*
X933692Y317061D01*
G01X935018Y292061D02*
X932518Y304561D01*
G01X933692Y292061D02*
X931192Y304561D01*
G01X932100Y277471D02*
X935018Y292061D01*
G01X930800Y277600D02*
X933692Y292061D01*
G01X929610Y292074D02*
X926800Y277998D01*
G01X930936Y292074D02*
X928100Y277869D01*
G01X927113Y304563D02*
X929610Y292074D01*
G01X928439Y304563D02*
X930936Y292074D01*
G01X929614Y317058D02*
X927113Y304563D01*
G01X930940Y317059D02*
X928439Y304563D01*
G01X931192Y304561D02*
X933692Y317061D01*
G01X932518Y304561D02*
X935018Y317061D01*
G01X933692Y292061D02*
X931192Y304561D01*
G01X935018Y292061D02*
X932518Y304561D01*
G01X930800Y277600D02*
X933692Y292061D01*
G01X932100Y277471D02*
X935018Y292061D01*
G01X930936Y292074D02*
X928100Y277869D01*
G01X929610Y292074D02*
X926800Y277998D01*
G01X928439Y304563D02*
X930936Y292074D01*
G01X927113Y304563D02*
X929610Y292074D01*
G01X930940Y317059D02*
X928439Y304563D01*
G01X929614Y317058D02*
X927113Y304563D01*
G01X923135Y304561D02*
X925635Y317061D01*
G01X924461Y304561D02*
X926961Y317061D01*
G01X925635Y292061D02*
X923135Y304561D01*
G01X926961Y292061D02*
X924461Y304561D01*
G01X922900Y278387D02*
X925635Y292061D01*
G01X924200Y278257D02*
X926961Y292061D01*
G01X924461Y304561D02*
X926961Y317061D01*
G01X923135Y304561D02*
X925635Y317061D01*
G01X926961Y292061D02*
X924461Y304561D01*
G01X925635Y292061D02*
X923135Y304561D01*
G01X924200Y278257D02*
X926961Y292061D01*
G01X922900Y278387D02*
X925635Y292061D01*
G01X919157Y304561D02*
X921657Y317061D01*
G01X920483Y304561D02*
X922983Y317061D01*
G01X921657Y292061D02*
X919157Y304561D01*
G01X922983Y292061D02*
X920483Y304561D01*
G01X919000Y278775D02*
X921657Y292061D01*
G01X920300Y278645D02*
X922983Y292061D01*
G01X920483Y304561D02*
X922983Y317061D01*
G01X919157Y304561D02*
X921657Y317061D01*
G01X922983Y292061D02*
X920483Y304561D01*
G01X921657Y292061D02*
X919157Y304561D01*
G01X920300Y278645D02*
X922983Y292061D01*
G01X919000Y278775D02*
X921657Y292061D01*
G01X917680D02*
X915100Y279163D01*
G01X919006Y292061D02*
X916400Y279033D01*
G01X915180Y304561D02*
X917680Y292061D01*
G01X916506Y304561D02*
X919006Y292061D01*
G01X917680Y317061D02*
X915180Y304561D01*
G01X919006Y317061D02*
X916506Y304561D01*
G01X919006Y292061D02*
X916400Y279033D01*
G01X917680Y292061D02*
X915100Y279163D01*
G01X916506Y304561D02*
X919006Y292061D01*
G01X915180Y304561D02*
X917680Y292061D01*
G01X919006Y317061D02*
X916506Y304561D01*
G01X917680Y317061D02*
X915180Y304561D01*
G01X911100D02*
X913600Y317061D01*
G01X912426Y304561D02*
X914926Y317061D01*
G01X913600Y292061D02*
X911100Y304561D01*
G01X914926Y292061D02*
X912426Y304561D01*
G01X911100Y279561D02*
X913600Y292061D01*
G01X912400Y279431D02*
X914926Y292061D01*
G01X912426Y304561D02*
X914926Y317061D01*
G01X911100Y304561D02*
X913600Y317061D01*
G01X914926Y292061D02*
X912426Y304561D01*
G01X913600Y292061D02*
X911100Y304561D01*
G01X912400Y279431D02*
X914926Y292061D01*
G01X911100Y279561D02*
X913600Y292061D01*
G01X935272Y329561D02*
X937772Y317061D01*
G01X936598Y329561D02*
X939098Y317061D01*
G01X937772Y342061D02*
X935272Y329561D01*
G01X939098Y342061D02*
X936598Y329561D01*
G01X935272Y354561D02*
X937772Y342061D01*
G01X936598Y354561D02*
X939098Y342061D01*
G01X939249Y329561D02*
X941749Y342061D01*
G01X940575Y329561D02*
X943075Y342061D01*
G01X941749Y317061D02*
X939249Y329561D01*
G01X943075Y317061D02*
X940575Y329561D01*
G01X936598D02*
X939098Y317061D01*
G01X935272Y329561D02*
X937772Y317061D01*
G01X939098Y342061D02*
X936598Y329561D01*
G01X937772Y342061D02*
X935272Y329561D01*
G01X936598Y354561D02*
X939098Y342061D01*
G01X935272Y354561D02*
X937772Y342061D01*
G01X940575Y329561D02*
X943075Y342061D01*
G01X939249Y329561D02*
X941749Y342061D01*
G01X943075Y317061D02*
X940575Y329561D01*
G01X941749Y317061D02*
X939249Y329561D01*
G01X935018Y342061D02*
X932518Y354561D01*
G01X933692Y342061D02*
X931192Y354561D01*
G01X932518Y329561D02*
X935018Y342061D01*
G01X931192Y329561D02*
X933692Y342061D01*
G01X935018Y317061D02*
X932518Y329561D01*
G01X933692Y317061D02*
X931192Y329561D01*
G01X927113Y329563D02*
X929614Y317058D01*
G01X928439Y329563D02*
X930940Y317059D01*
G01X929614Y342058D02*
X927113Y329563D01*
G01X930940Y342059D02*
X928439Y329563D01*
G01X927113Y354563D02*
X929614Y342058D01*
G01X928439Y354563D02*
X930940Y342059D01*
G01X933692Y342061D02*
X931192Y354561D01*
G01X935018Y342061D02*
X932518Y354561D01*
G01X931192Y329561D02*
X933692Y342061D01*
G01X932518Y329561D02*
X935018Y342061D01*
G01X933692Y317061D02*
X931192Y329561D01*
G01X935018Y317061D02*
X932518Y329561D01*
G01X928439Y329563D02*
X930940Y317059D01*
G01X927113Y329563D02*
X929614Y317058D01*
G01X930940Y342059D02*
X928439Y329563D01*
G01X929614Y342058D02*
X927113Y329563D01*
G01X928439Y354563D02*
X930940Y342059D01*
G01X927113Y354563D02*
X929614Y342058D01*
G01X925635Y342061D02*
X923135Y354561D01*
G01X926961Y342061D02*
X924461Y354561D01*
G01X923135Y329561D02*
X925635Y342061D01*
G01X924461Y329561D02*
X926961Y342061D01*
G01X925635Y317061D02*
X923135Y329561D01*
G01X926961Y317061D02*
X924461Y329561D01*
G01X926961Y342061D02*
X924461Y354561D01*
G01X925635Y342061D02*
X923135Y354561D01*
G01X924461Y329561D02*
X926961Y342061D01*
G01X923135Y329561D02*
X925635Y342061D01*
G01X926961Y317061D02*
X924461Y329561D01*
G01X925635Y317061D02*
X923135Y329561D01*
G01X921657Y342061D02*
X919157Y354561D01*
G01X922983Y342061D02*
X920483Y354561D01*
G01X919157Y329561D02*
X921657Y342061D01*
G01X920483Y329561D02*
X922983Y342061D01*
G01X921657Y317061D02*
X919157Y329561D01*
G01X922983Y317061D02*
X920483Y329561D01*
G01X922983Y342061D02*
X920483Y354561D01*
G01X921657Y342061D02*
X919157Y354561D01*
G01X920483Y329561D02*
X922983Y342061D01*
G01X919157Y329561D02*
X921657Y342061D01*
G01X922983Y317061D02*
X920483Y329561D01*
G01X921657Y317061D02*
X919157Y329561D01*
G01X915180D02*
X917680Y317061D01*
G01X916506Y329561D02*
X919006Y317061D01*
G01X917680Y342061D02*
X915180Y329561D01*
G01X919006Y342061D02*
X916506Y329561D01*
G01X915180Y354561D02*
X917680Y342061D01*
G01X916506Y354561D02*
X919006Y342061D01*
G01X916506Y329561D02*
X919006Y317061D01*
G01X915180Y329561D02*
X917680Y317061D01*
G01X919006Y342061D02*
X916506Y329561D01*
G01X917680Y342061D02*
X915180Y329561D01*
G01X916506Y354561D02*
X919006Y342061D01*
G01X915180Y354561D02*
X917680Y342061D01*
G01X913600D02*
X911100Y354561D01*
G01X914926Y342061D02*
X912426Y354561D01*
G01X911100Y329561D02*
X913600Y342061D01*
G01X912426Y329561D02*
X914926Y342061D01*
G01X913600Y317061D02*
X911100Y329561D01*
G01X914926Y317061D02*
X912426Y329561D01*
G01X914926Y342061D02*
X912426Y354561D01*
G01X913600Y342061D02*
X911100Y354561D01*
G01X912426Y329561D02*
X914926Y342061D01*
G01X911100Y329561D02*
X913600Y342061D01*
G01X914926Y317061D02*
X912426Y329561D01*
G01X913600Y317061D02*
X911100Y329561D01*
G01X937772Y367061D02*
X935272Y354561D01*
G01X939098Y367061D02*
X936598Y354561D01*
G01X935272Y379561D02*
X937772Y367061D01*
G01X936598Y379561D02*
X939098Y367061D01*
G01X941749D02*
X939249Y379561D01*
G01X943075Y367061D02*
X940575Y379561D01*
G01X939249Y354561D02*
X941749Y367061D01*
G01X940575Y354561D02*
X943075Y367061D01*
G01X941749Y342061D02*
X939249Y354561D01*
G01X943075Y342061D02*
X940575Y354561D01*
G01X939098Y367061D02*
X936598Y354561D01*
G01X937772Y367061D02*
X935272Y354561D01*
G01X936598Y379561D02*
X939098Y367061D01*
G01X935272Y379561D02*
X937772Y367061D01*
G01X943075D02*
X940575Y379561D01*
G01X941749Y367061D02*
X939249Y379561D01*
G01X940575Y354561D02*
X943075Y367061D01*
G01X939249Y354561D02*
X941749Y367061D01*
G01X943075Y342061D02*
X940575Y354561D01*
G01X941749Y342061D02*
X939249Y354561D01*
G01X935018Y367061D02*
X932518Y379561D01*
G01X933692Y367061D02*
X931192Y379561D01*
G01X932518Y354561D02*
X935018Y367061D01*
G01X931192Y354561D02*
X933692Y367061D01*
G01X929614Y367058D02*
X927113Y354563D01*
G01X930940Y367059D02*
X928439Y354563D01*
G01X927113Y379563D02*
X929614Y367059D01*
G01X928439Y379563D02*
X930940Y367059D01*
G01X933692Y367061D02*
X931192Y379561D01*
G01X935018Y367061D02*
X932518Y379561D01*
G01X931192Y354561D02*
X933692Y367061D01*
G01X932518Y354561D02*
X935018Y367061D01*
G01X930940Y367059D02*
X928439Y354563D01*
G01X929614Y367058D02*
X927113Y354563D01*
G01X928439Y379563D02*
X930940Y367059D01*
G01X927113Y379563D02*
X929614Y367059D01*
G01X925635Y367061D02*
X923135Y379561D01*
G01X926961Y367061D02*
X924461Y379561D01*
G01X923135Y354561D02*
X925635Y367061D01*
G01X924461Y354561D02*
X926961Y367061D01*
G01D02*
X924461Y379561D01*
G01X925635Y367061D02*
X923135Y379561D01*
G01X924461Y354561D02*
X926961Y367061D01*
G01X923135Y354561D02*
X925635Y367061D01*
G01X921657D02*
X919157Y379561D01*
G01X922983Y367061D02*
X920483Y379561D01*
G01X919157Y354561D02*
X921657Y367061D01*
G01X920483Y354561D02*
X922983Y367061D01*
G01D02*
X920483Y379561D01*
G01X921657Y367061D02*
X919157Y379561D01*
G01X920483Y354561D02*
X922983Y367061D01*
G01X919157Y354561D02*
X921657Y367061D01*
G01X917680D02*
X915180Y354561D01*
G01X919006Y367061D02*
X916506Y354561D01*
G01X915180Y379561D02*
X917680Y367061D01*
G01X916506Y379561D02*
X919006Y367061D01*
G01D02*
X916506Y354561D01*
G01X917680Y367061D02*
X915180Y354561D01*
G01X916506Y379561D02*
X919006Y367061D01*
G01X915180Y379561D02*
X917680Y367061D01*
G01X913600D02*
X911100Y379561D01*
G01X914926Y367061D02*
X912426Y379561D01*
G01X911100Y354561D02*
X913600Y367061D01*
G01X912426Y354561D02*
X914926Y367061D01*
G01D02*
X912426Y379561D01*
G01X913600Y367061D02*
X911100Y379561D01*
G01X912426Y354561D02*
X914926Y367061D01*
G01X911100Y354561D02*
X913600Y367061D01*
G01X937772Y392061D02*
X935272Y379561D01*
G01X939098Y392061D02*
X936598Y379561D01*
G01X935272Y404561D02*
X937772Y392061D01*
G01X936598Y404561D02*
X939098Y392061D01*
G01X937772Y417061D02*
X935272Y404561D01*
G01X939098Y417061D02*
X936598Y404561D01*
G01X939249D02*
X941749Y417061D01*
G01X940575Y404561D02*
X943075Y417061D01*
G01X941749Y392061D02*
X939249Y404561D01*
G01X943075Y392061D02*
X940575Y404561D01*
G01X939249Y379561D02*
X941749Y392061D01*
G01X940575Y379561D02*
X943075Y392061D01*
G01X939098D02*
X936598Y379561D01*
G01X937772Y392061D02*
X935272Y379561D01*
G01X936598Y404561D02*
X939098Y392061D01*
G01X935272Y404561D02*
X937772Y392061D01*
G01X939098Y417061D02*
X936598Y404561D01*
G01X937772Y417061D02*
X935272Y404561D01*
G01X940575D02*
X943075Y417061D01*
G01X939249Y404561D02*
X941749Y417061D01*
G01X943075Y392061D02*
X940575Y404561D01*
G01X941749Y392061D02*
X939249Y404561D01*
G01X940575Y379561D02*
X943075Y392061D01*
G01X939249Y379561D02*
X941749Y392061D01*
G01X932518Y404561D02*
X935018Y417061D01*
G01X931192Y404561D02*
X933692Y417061D01*
G01X935018Y392061D02*
X932518Y404561D01*
G01X933692Y392061D02*
X931192Y404561D01*
G01X932518Y379561D02*
X935018Y392061D01*
G01X931192Y379561D02*
X933692Y392061D01*
G01X929598Y391974D02*
X927113Y379563D01*
G01X930874Y391724D02*
X928439Y379563D01*
G01X930935Y392041D02*
X930874Y391724D01*
G01X929614Y392057D02*
X929598Y391974D01*
G01X930874Y391724D02*
X928439Y379563D01*
G01X928430Y397896D02*
X929610Y392080D01*
G01X928423Y404481D02*
X930889Y392316D01*
G01X927148Y404225D02*
X928430Y397896D01*
G01X928423Y404481D02*
X930889Y392316D01*
G01X927102Y404485D02*
X927148Y404225D01*
G01X928423Y404481D02*
X930889Y392316D01*
G01X927148Y404736D02*
X927102Y404485D01*
G01X930939Y417063D02*
X928423Y404481D01*
G01X929616Y417078D02*
X927148Y404736D01*
G01X930939Y417063D02*
X928423Y404481D01*
G01X931192Y404561D02*
X933692Y417061D01*
G01X932518Y404561D02*
X935018Y417061D01*
G01X933692Y392061D02*
X931192Y404561D01*
G01X935018Y392061D02*
X932518Y404561D01*
G01X931192Y379561D02*
X933692Y392061D01*
G01X932518Y379561D02*
X935018Y392061D01*
G01X930874Y391724D02*
X928439Y379563D01*
G01X929598Y391974D02*
X927113Y379563D01*
G01X929614Y392057D02*
X929598Y391974D01*
G01X930935Y392041D02*
X930874Y391724D01*
G01X929598Y391974D02*
X927113Y379563D01*
G01X928423Y404481D02*
X930889Y392316D01*
G01X928430Y397896D02*
X929610Y392080D01*
G01X927148Y404225D02*
X928430Y397896D01*
G01X927102Y404485D02*
X927148Y404225D01*
G01X930939Y417063D02*
X928423Y404481D01*
G01X927148Y404736D02*
X927102Y404485D01*
G01X929616Y417078D02*
X927148Y404736D01*
G01X922093Y409905D02*
X918551Y427747D01*
G01X926961Y392061D02*
X919773Y428269D01*
G01X925635Y392062D02*
X922093Y409905D01*
G01X926961Y392061D02*
X919773Y428269D01*
G01X923135Y379561D02*
X925635Y392062D01*
G01X924461Y379561D02*
X926961Y392061D01*
G01D02*
X919773Y428269D01*
G01X922093Y409905D02*
X918551Y427747D01*
G01X925635Y392062D02*
X922093Y409905D01*
G01X924461Y379561D02*
X926961Y392061D01*
G01X923135Y379561D02*
X925635Y392062D01*
G01X921657Y392061D02*
X918180Y409441D01*
G01X922983Y392061D02*
X919402Y409964D01*
G01X919157Y379561D02*
X921657Y392061D01*
G01X920483Y379561D02*
X922983Y392061D01*
G01D02*
X919402Y409964D01*
G01X921657Y392061D02*
X918180Y409441D01*
G01X920483Y379561D02*
X922983Y392061D01*
G01X919157Y379561D02*
X921657Y392061D01*
G01X917680D02*
X915180Y379561D01*
G01X919006Y392061D02*
X916506Y379561D01*
G01X915284Y404038D02*
X917680Y392061D01*
G01X916506Y404561D02*
X919006Y392061D01*
G01D02*
X916506Y379561D01*
G01X917680Y392061D02*
X915180Y379561D01*
G01X916506Y404561D02*
X919006Y392061D01*
G01X915284Y404038D02*
X917680Y392061D01*
G01X911100Y379561D02*
X913600Y392061D01*
G01X912426Y379561D02*
X914991Y392384D01*
G01X912426Y379561D02*
X914991Y392384D01*
G01X911100Y379561D02*
X913600Y392061D01*
G01X935272Y429561D02*
X937772Y417061D01*
G01X936598Y429561D02*
X939098Y417061D01*
G01X937772Y442061D02*
X935272Y429561D01*
G01X939098Y442061D02*
X936598Y429561D01*
G01X934878Y456526D02*
X937772Y442061D01*
G01X936100Y457049D02*
X939098Y442061D01*
G01X939249Y429561D02*
X941749Y442061D01*
G01X940575Y429561D02*
X943075Y442061D01*
G01X941749Y417061D02*
X939249Y429561D01*
G01X943075Y417061D02*
X940575Y429561D01*
G01X936598D02*
X939098Y417061D01*
G01X935272Y429561D02*
X937772Y417061D01*
G01X939098Y442061D02*
X936598Y429561D01*
G01X937772Y442061D02*
X935272Y429561D01*
G01X936100Y457049D02*
X939098Y442061D01*
G01X934878Y456526D02*
X937772Y442061D01*
G01X940575Y429561D02*
X943075Y442061D01*
G01X939249Y429561D02*
X941749Y442061D01*
G01X943075Y417061D02*
X940575Y429561D01*
G01X941749Y417061D02*
X939249Y429561D01*
G01X935018Y417061D02*
X928579Y449255D01*
G01X933692Y417061D02*
X927357Y448732D01*
G01X925627Y439699D02*
X929616Y417078D01*
G01X926858Y440209D02*
X930939Y417063D01*
G01X933692Y417061D02*
X927357Y448732D01*
G01X935018Y417061D02*
X928579Y449255D01*
G01X926858Y440209D02*
X930939Y417063D01*
G01X925627Y439699D02*
X929616Y417078D01*
G01X941749Y442061D02*
X938778Y456915D01*
G01X943075Y442061D02*
X940000Y457438D01*
G01X943075Y442061D02*
X940000Y457438D01*
G01X941749Y442061D02*
X938778Y456915D01*
G01X943700Y144600D02*
Y185793D01*
G01X945000D02*
Y144600D01*
G01Y185793D02*
Y144600D01*
G01X943700D02*
Y185793D01*
G01X943046Y186654D02*
G03X942693Y186800I-353J-354D01*
G01Y188100D02*
G02X943965Y187574I0J-1801D01*
G01X943554Y186146D02*
X943046Y186654D01*
G01X943965Y187574D02*
X944474Y187065D01*
G01X943700Y185793D02*
G03X943554Y186146I-500J0D01*
G01X944474Y187065D02*
G02X945000Y185793I-1275J-1272D01*
G01X944474Y187065D02*
G02X945000Y185793I-1275J-1272D01*
G01X943700D02*
G03X943554Y186146I-500J0D01*
G01X943965Y187574D02*
X944474Y187065D01*
G01X943554Y186146D02*
X943046Y186654D01*
G01X942693Y188100D02*
G02X943965Y187574I0J-1801D01*
G01X943046Y186654D02*
G03X942693Y186800I-353J-354D01*
G01X974100Y263600D02*
Y298295D01*
G01Y263600D02*
Y298295D01*
G01X966200Y263800D02*
Y299081D01*
G01X967500Y263800D02*
Y298951D01*
G01X970100Y263700D02*
Y298693D01*
G01X971400Y263700D02*
Y298563D01*
G01X967500Y263800D02*
Y298951D01*
G01X966200Y263800D02*
Y299081D01*
G01X971400Y263700D02*
Y298563D01*
G01X970100Y263700D02*
Y298693D01*
G01X962300Y263600D02*
Y299469D01*
G01X963600Y263600D02*
Y299339D01*
G01Y263600D02*
Y299339D01*
G01X962300Y263600D02*
Y299469D01*
G01X958400Y263800D02*
Y299857D01*
G01X959700Y263800D02*
Y299728D01*
G01X955700Y263500D02*
Y300126D01*
G01X954400Y263500D02*
Y300255D01*
G01X959700Y263800D02*
Y299728D01*
G01X958400Y263800D02*
Y299857D01*
G01X954400Y263500D02*
Y300255D01*
G01X955700Y263500D02*
Y300126D01*
G01X950500Y263600D02*
Y300644D01*
G01X951800Y263600D02*
Y300514D01*
G01Y263600D02*
Y300514D01*
G01X950500Y263600D02*
Y300644D01*
G01X974100Y298295D02*
X980353Y329561D01*
G01X974100Y298295D02*
X980353Y329561D01*
G01X966200Y299081D02*
X972296Y329561D01*
G01X967500Y298951D02*
X973622Y329561D01*
G01X970100Y298693D02*
X976274Y329561D01*
G01X971400Y298563D02*
X977600Y329561D01*
G01X967500Y298951D02*
X973622Y329561D01*
G01X966200Y299081D02*
X972296Y329561D01*
G01X971400Y298563D02*
X977600Y329561D01*
G01X970100Y298693D02*
X976274Y329561D01*
G01X962300Y299469D02*
X968318Y329561D01*
G01X963600Y299339D02*
X969644Y329561D01*
G01X963600Y299339D02*
X969644Y329561D01*
G01X962300Y299469D02*
X968318Y329561D01*
G01X958400Y299857D02*
X964341Y329561D01*
G01X959700Y299728D02*
X965667Y329561D01*
G01X955700Y300126D02*
X961587Y329561D01*
G01X954400Y300255D02*
X960261Y329561D01*
G01X959700Y299728D02*
X965667Y329561D01*
G01X958400Y299857D02*
X964341Y329561D01*
G01X954400Y300255D02*
X960261Y329561D01*
G01X955700Y300126D02*
X961587Y329561D01*
G01X950500Y300644D02*
X956283Y329561D01*
G01X951800Y300514D02*
X957609Y329561D01*
G01X951800Y300514D02*
X957609Y329561D01*
G01X950500Y300644D02*
X956283Y329561D01*
G01X972296D02*
X967296Y354561D01*
G01X973622Y329561D02*
X968622Y354561D01*
G01X976274Y329561D02*
X971274Y354561D01*
G01X977600Y329561D02*
X972600Y354561D01*
G01X973622Y329561D02*
X968622Y354561D01*
G01X972296Y329561D02*
X967296Y354561D01*
G01X977600Y329561D02*
X972600Y354561D01*
G01X976274Y329561D02*
X971274Y354561D01*
G01X968318Y329561D02*
X963318Y354561D01*
G01X969644Y329561D02*
X964644Y354561D01*
G01X969644Y329561D02*
X964644Y354561D01*
G01X968318Y329561D02*
X963318Y354561D01*
G01X964341Y329561D02*
X959341Y354561D01*
G01X965667Y329561D02*
X960667Y354561D01*
G01X961587Y329561D02*
X956587Y354561D01*
G01X960261Y329561D02*
X955261Y354561D01*
G01X965667Y329561D02*
X960667Y354561D01*
G01X964341Y329561D02*
X959341Y354561D01*
G01X960261Y329561D02*
X955261Y354561D01*
G01X961587Y329561D02*
X956587Y354561D01*
G01X956283Y329561D02*
X951283Y354561D01*
G01X957609Y329561D02*
X952609Y354561D01*
G01X957609Y329561D02*
X952609Y354561D01*
G01X956283Y329561D02*
X951283Y354561D01*
G01X967296D02*
X972296Y379561D01*
G01X968622Y354561D02*
X973622Y379561D01*
G01X971274Y354561D02*
X976274Y379561D01*
G01X972600Y354561D02*
X977600Y379561D01*
G01X968622Y354561D02*
X973622Y379561D01*
G01X967296Y354561D02*
X972296Y379561D01*
G01X972600Y354561D02*
X977600Y379561D01*
G01X971274Y354561D02*
X976274Y379561D01*
G01X963318Y354561D02*
X968318Y379561D01*
G01X964644Y354561D02*
X969644Y379561D01*
G01X964644Y354561D02*
X969644Y379561D01*
G01X963318Y354561D02*
X968318Y379561D01*
G01X959341Y354561D02*
X964341Y379561D01*
G01X960667Y354561D02*
X965667Y379561D01*
G01X956587Y354561D02*
X961587Y379561D01*
G01X955261Y354561D02*
X960261Y379561D01*
G01X960667Y354561D02*
X965667Y379561D01*
G01X959341Y354561D02*
X964341Y379561D01*
G01X955261Y354561D02*
X960261Y379561D01*
G01X956587Y354561D02*
X961587Y379561D01*
G01X951283Y354561D02*
X956283Y379561D01*
G01X952609Y354561D02*
X957609Y379561D01*
G01X952609Y354561D02*
X957609Y379561D01*
G01X951283Y354561D02*
X956283Y379561D01*
G01X967296Y404561D02*
X974210Y439133D01*
G01X968622Y404561D02*
X975533Y439118D01*
G01X972296Y379561D02*
X967296Y404561D01*
G01X973622Y379561D02*
X968622Y404561D01*
G01X971274D02*
X978748Y441933D01*
G01X972600Y404561D02*
X980071Y441918D01*
G01X976274Y379561D02*
X971274Y404561D01*
G01X977600Y379561D02*
X972600Y404561D01*
G01X968622D02*
X975533Y439118D01*
G01X967296Y404561D02*
X974210Y439133D01*
G01X973622Y379561D02*
X968622Y404561D01*
G01X972296Y379561D02*
X967296Y404561D01*
G01X972600D02*
X980071Y441918D01*
G01X971274Y404561D02*
X978748Y441933D01*
G01X977600Y379561D02*
X972600Y404561D01*
G01X976274Y379561D02*
X971274Y404561D01*
G01X963318D02*
X969957Y437756D01*
G01X964644Y404561D02*
X971280Y437741D01*
G01X968318Y379561D02*
X963318Y404561D01*
G01X969644Y379561D02*
X964644Y404561D01*
G01D02*
X971280Y437741D01*
G01X963318Y404561D02*
X969957Y437756D01*
G01X969644Y379561D02*
X964644Y404561D01*
G01X968318Y379561D02*
X963318Y404561D01*
G01X959341D02*
X964606Y430888D01*
G01X960667Y404561D02*
X965929Y430873D01*
G01X964341Y379561D02*
X959341Y404561D01*
G01X965667Y379561D02*
X960667Y404561D01*
G01X956587D02*
X961587Y429561D01*
G01X955261Y404561D02*
X960261Y429561D01*
G01X961587Y379561D02*
X956587Y404561D01*
G01X960261Y379561D02*
X955261Y404561D01*
G01X960667D02*
X965929Y430873D01*
G01X959341Y404561D02*
X964606Y430888D01*
G01X965667Y379561D02*
X960667Y404561D01*
G01X964341Y379561D02*
X959341Y404561D01*
G01X955261D02*
X960261Y429561D01*
G01X956587Y404561D02*
X961587Y429561D01*
G01X960261Y379561D02*
X955261Y404561D01*
G01X961587Y379561D02*
X956587Y404561D01*
G01X951283D02*
X956283Y429561D01*
G01X952609Y404561D02*
X957609Y429561D01*
G01X956283Y379561D02*
X951283Y404561D01*
G01X957609Y379561D02*
X952609Y404561D01*
G01D02*
X957609Y429561D01*
G01X951283Y404561D02*
X956283Y429561D01*
G01X957609Y379561D02*
X952609Y404561D01*
G01X956283Y379561D02*
X951283Y404561D01*
G01X974210Y439133D02*
X968769Y469990D01*
G01X975533Y439118D02*
X970000Y470500D01*
G01X975533Y439118D02*
X970000Y470500D01*
G01X974210Y439133D02*
X968769Y469990D01*
G01X971280Y437741D02*
X966025Y467544D01*
G01X969957Y437756D02*
X967376Y452395D01*
G01X971280Y437741D02*
X966025Y467544D01*
G01X971280Y437741D02*
X966025Y467544D01*
G01X969957Y437756D02*
X967376Y452395D01*
G01X965929Y430873D02*
X960000Y464500D01*
G01X964606Y430888D02*
X961687Y447440D01*
G01X965929Y430873D02*
X960000Y464500D01*
G01X961587Y429561D02*
X955700Y458996D01*
G01X960261Y429561D02*
X954478Y458473D01*
G01X965929Y430873D02*
X960000Y464500D01*
G01X964606Y430888D02*
X961687Y447440D01*
G01X960261Y429561D02*
X954478Y458473D01*
G01X961587Y429561D02*
X955700Y458996D01*
G01X956283Y429561D02*
X950578Y458085D01*
G01X957609Y429561D02*
X951800Y458608D01*
G01X957609Y429561D02*
X951800Y458608D01*
G01X956283Y429561D02*
X950578Y458085D01*
G01X978748Y441933D02*
X973221Y473275D01*
G01X980071Y441918D02*
X974452Y473785D01*
G01X980071Y441918D02*
X974452Y473785D01*
G01X978748Y441933D02*
X973221Y473275D01*
G01X967376Y452395D02*
X964794Y467034D01*
G01X967376Y452395D02*
X964794Y467034D01*
G01X961687Y447440D02*
X958769Y463990D01*
G01X961687Y447440D02*
X958769Y463990D01*
G01X1006318Y107549D02*
Y111060D01*
G01X1007618D02*
Y107665D01*
G01X1006890Y104346D02*
X1006318Y107549D01*
G01X1007618Y107665D02*
X1008120Y104857D01*
G01X1009475Y100652D02*
X1006890Y104346D01*
G01X1008120Y104857D02*
X1010409Y101586D01*
G01X1005226Y98653D02*
X1013693Y92726D01*
G01X1006160Y99587D02*
X1014222Y93943D01*
G01X1002504Y102541D02*
X1005226Y98653D01*
G01X1003735Y103051D02*
X1006160Y99587D01*
G01X1002037Y105187D02*
X1002504Y102541D01*
G01X1003318Y105413D02*
X1003735Y103051D01*
G01X1002018Y117500D02*
Y105206D01*
G01X1003318Y117450D02*
Y105413D01*
G01X1001961Y96143D02*
X1012323Y88889D01*
G01X1002895Y97077D02*
X1012852Y90106D01*
G01X997200Y102945D02*
X1001961Y96143D01*
G01X998500Y103355D02*
X1002895Y97077D01*
G01X997200Y114300D02*
Y102945D01*
G01X998500Y114300D02*
Y103355D01*
G01X993500Y100533D02*
Y110710D01*
G01X994800D02*
Y100943D01*
G01X1000687Y90264D02*
X993500Y100533D01*
G01X994800Y100943D02*
X1001621Y91198D01*
G01X1007339Y85607D02*
X1000687Y90264D01*
G01X1001621Y91198D02*
X1007868Y86824D01*
G01X1040465Y78568D02*
X1007339Y85607D01*
G01X1007868Y86824D02*
X1026674Y82829D01*
G01X989873Y96818D02*
Y111648D01*
G01X991173Y96933D02*
Y111771D01*
G01X991297Y88738D02*
X989873Y96818D01*
G01X992470Y89574D02*
X991173Y96933D01*
G01X1009765Y78495D02*
X991297Y88738D01*
G01X1010435Y79610D02*
X992470Y89574D01*
G01X1008120Y104857D02*
X1010409Y101586D01*
G01X1009475Y100652D02*
X1006890Y104346D01*
G01X1007618Y107665D02*
X1008120Y104857D01*
G01X1006890Y104346D02*
X1006318Y107549D01*
G01X1007618Y111060D02*
Y107665D01*
G01X1006318Y107549D02*
Y111060D01*
G01X1006160Y99587D02*
X1014222Y93943D01*
G01X1005226Y98653D02*
X1013693Y92726D01*
G01X1003735Y103051D02*
X1006160Y99587D01*
G01X1002504Y102541D02*
X1005226Y98653D01*
G01X1003318Y105413D02*
X1003735Y103051D01*
G01X1002037Y105187D02*
X1002504Y102541D01*
G01X1003318Y117450D02*
Y105413D01*
G01X1002018Y117500D02*
Y105206D01*
G01X1002895Y97077D02*
X1012852Y90106D01*
G01X1001961Y96143D02*
X1012323Y88889D01*
G01X998500Y103355D02*
X1002895Y97077D01*
G01X997200Y102945D02*
X1001961Y96143D01*
G01X998500Y114300D02*
Y103355D01*
G01X997200Y114300D02*
Y102945D01*
G01X1040465Y78568D02*
X1007339Y85607D01*
G01X1040465Y78568D02*
X1007339Y85607D01*
G01X1040465Y78568D02*
X1007339Y85607D01*
G01X1007868Y86824D02*
X1026674Y82829D01*
G01X1040465Y78568D02*
X1007339Y85607D01*
G01X1001621Y91198D02*
X1007868Y86824D01*
G01X1007339Y85607D02*
X1000687Y90264D01*
G01X994800Y100943D02*
X1001621Y91198D01*
G01X1000687Y90264D02*
X993500Y100533D01*
G01X994800Y110710D02*
Y100943D01*
G01X993500Y100533D02*
Y110710D01*
G01X991173Y96933D02*
Y111771D01*
G01X989873Y96818D02*
Y111648D01*
G01X992470Y89574D02*
X991173Y96933D01*
G01X991297Y88738D02*
X989873Y96818D01*
G01X1010435Y79610D02*
X992470Y89574D01*
G01X1009765Y78495D02*
X991297Y88738D01*
G01X993800Y267399D02*
X1057818Y630490D01*
G01X995100Y267285D02*
X1059139Y630490D01*
G01X993800Y263600D02*
Y267399D01*
G01X995100Y263600D02*
Y267285D01*
G01X997850Y271615D02*
X1062861Y640315D01*
G01X999150Y271501D02*
X1064182Y640315D01*
G01X997850Y263694D02*
Y271615D01*
G01X999150Y263450D02*
Y271501D01*
G01X1001700Y267399D02*
X1076955Y694208D01*
G01X1003000Y267285D02*
X1078276Y694208D01*
G01X1001700Y263300D02*
Y267399D01*
G01X1003000Y263300D02*
Y267285D01*
G01X1006440Y273980D02*
X1101553Y698500D01*
G01X1007716Y273725D02*
X1102887Y698505D01*
G01X1005600Y269212D02*
X1006440Y273980D01*
G01X1006900Y269095D02*
X1007716Y273725D01*
G01X1005600Y263500D02*
Y269212D01*
G01X1006900Y263500D02*
Y269095D01*
G01X995100Y267285D02*
X1059139Y630490D01*
G01X993800Y267399D02*
X1057818Y630490D01*
G01X995100Y263600D02*
Y267285D01*
G01X993800Y263600D02*
Y267399D01*
G01X999150Y271501D02*
X1064182Y640315D01*
G01X997850Y271615D02*
X1062861Y640315D01*
G01X999150Y263450D02*
Y271501D01*
G01X997850Y263694D02*
Y271615D01*
G01X1003000Y267285D02*
X1078276Y694208D01*
G01X1001700Y267399D02*
X1076955Y694208D01*
G01X1003000Y263300D02*
Y267285D01*
G01X1001700Y263300D02*
Y267399D01*
G01X1007716Y273725D02*
X1102887Y698505D01*
G01X1006440Y273980D02*
X1101553Y698500D01*
G01X1006900Y269095D02*
X1007716Y273725D01*
G01X1005600Y269212D02*
X1006440Y273980D01*
G01X1006900Y263500D02*
Y269095D01*
G01X1005600Y263500D02*
Y269212D01*
G01X978000Y263500D02*
Y297907D01*
G01X979300Y263500D02*
Y297777D01*
G01X985900Y264136D02*
Y298162D01*
G01X987200Y264430D02*
Y298048D01*
G01X989900Y292351D02*
Y264288D01*
G01X991200Y292237D02*
Y263994D01*
G01X979300Y263500D02*
Y297777D01*
G01X978000Y263500D02*
Y297907D01*
G01X987200Y264430D02*
Y298048D01*
G01X985900Y264136D02*
Y298162D01*
G01X991200Y292237D02*
Y263994D01*
G01X989900Y292351D02*
Y264288D01*
G01X975400Y263600D02*
Y298165D01*
G01Y263600D02*
Y298165D01*
G01X978000Y297907D02*
X984331Y329561D01*
G01X979300Y297777D02*
X985657Y329561D01*
G01X985900Y298162D02*
X1004153Y401635D01*
G01X987200Y298048D02*
X1005453Y401521D01*
G01X1009410Y402955D02*
X989900Y292351D01*
G01X1010710Y402841D02*
X991200Y292237D01*
G01X979300Y297777D02*
X985657Y329561D01*
G01X978000Y297907D02*
X984331Y329561D01*
G01X987200Y298048D02*
X1005453Y401521D01*
G01X985900Y298162D02*
X1004153Y401635D01*
G01X1010710Y402841D02*
X991200Y292237D01*
G01X1009410Y402955D02*
X989900Y292351D01*
G01X975400Y298165D02*
X981679Y329561D01*
G01X975400Y298165D02*
X981679Y329561D01*
G01X984331D02*
X979331Y354561D01*
G01X985657Y329561D02*
X980657Y354561D01*
G01X985657Y329561D02*
X980657Y354561D01*
G01X984331Y329561D02*
X979331Y354561D01*
G01X980353Y329561D02*
X975353Y354561D01*
G01X981679Y329561D02*
X976679Y354561D01*
G01X981679Y329561D02*
X976679Y354561D01*
G01X980353Y329561D02*
X975353Y354561D01*
G01X979331D02*
X984331Y379561D01*
G01X980657Y354561D02*
X985657Y379561D01*
G01X980657Y354561D02*
X985657Y379561D01*
G01X979331Y354561D02*
X984331Y379561D01*
G01X975353Y354561D02*
X980353Y379561D01*
G01X976679Y354561D02*
X981679Y379561D01*
G01X976679Y354561D02*
X981679Y379561D01*
G01X975353Y354561D02*
X980353Y379561D01*
G01X979331Y404561D02*
X987289Y444352D01*
G01X980657Y404561D02*
X988612Y444337D01*
G01X984331Y379561D02*
X979331Y404561D01*
G01X985657Y379561D02*
X980657Y404561D01*
G01X1004153Y403373D02*
X990104Y483048D01*
G01X1005453Y403487D02*
X991335Y483558D01*
G01X1004153Y401635D02*
Y403373D01*
G01X1005453Y401521D02*
Y403487D01*
G01X994560Y488927D02*
X1009410Y404708D01*
G01X980657Y404561D02*
X988612Y444337D01*
G01X979331Y404561D02*
X987289Y444352D01*
G01X985657Y379561D02*
X980657Y404561D01*
G01X984331Y379561D02*
X979331Y404561D01*
G01X1005453Y403487D02*
X991335Y483558D01*
G01X1004153Y403373D02*
X990104Y483048D01*
G01X1005453Y401521D02*
Y403487D01*
G01X1004153Y401635D02*
Y403373D01*
G01X994560Y488927D02*
X1009410Y404708D01*
G01X975353Y404561D02*
X983083Y443209D01*
G01X976679Y404561D02*
X984406Y443194D01*
G01X980353Y379561D02*
X975353Y404561D01*
G01X981679Y379561D02*
X976679Y404561D01*
G01D02*
X984406Y443194D01*
G01X975353Y404561D02*
X983083Y443209D01*
G01X981679Y379561D02*
X976679Y404561D01*
G01X980353Y379561D02*
X975353Y404561D01*
G01X987289Y444352D02*
X980985Y480095D01*
G01X988612Y444337D02*
X982217Y480604D01*
G01X995791Y489437D02*
X1010710Y404822D01*
G01X988612Y444337D02*
X982217Y480604D01*
G01X987289Y444352D02*
X980985Y480095D01*
G01X995791Y489437D02*
X1010710Y404822D01*
G01X983083Y443209D02*
X977191Y476610D01*
G01X984406Y443194D02*
X978422Y477120D01*
G01X984406Y443194D02*
X978422Y477120D01*
G01X983083Y443209D02*
X977191Y476610D01*
G01X1019156Y72396D02*
X1009765Y78495D01*
G01X1019662Y73618D02*
X1010435Y79610D01*
G01X1053800Y65033D02*
X1019156Y72396D01*
G01X1054306Y66255D02*
X1019662Y73618D01*
G01D02*
X1010435Y79610D01*
G01X1019156Y72396D02*
X1009765Y78495D01*
G01X1054306Y66255D02*
X1019662Y73618D01*
G01X1053800Y65033D02*
X1019156Y72396D01*
G01X1010611Y106856D02*
X1010300Y108623D01*
G01X1011842Y107366D02*
X1011600Y108737D01*
G01X1012073Y104770D02*
X1010611Y106856D01*
G01X1013006Y105704D02*
X1011842Y107366D01*
G01X1015184Y102592D02*
X1012073Y104770D01*
G01X1015694Y103823D02*
X1013006Y105704D01*
G01X1026600Y100579D02*
X1015184Y102592D01*
G01X1026600Y101900D02*
X1015694Y103823D01*
G01X1042014Y103297D02*
X1026600Y100579D01*
G01X1042014Y104618D02*
X1026600Y101900D01*
G01X1060521Y100033D02*
X1042014Y103297D01*
G01X1060521Y101354D02*
X1042014Y104618D01*
G01X1011842Y107366D02*
X1011600Y108737D01*
G01X1010611Y106856D02*
X1010300Y108623D01*
G01X1013006Y105704D02*
X1011842Y107366D01*
G01X1012073Y104770D02*
X1010611Y106856D01*
G01X1015694Y103823D02*
X1013006Y105704D01*
G01X1015184Y102592D02*
X1012073Y104770D01*
G01X1026600Y101900D02*
X1015694Y103823D01*
G01X1026600Y100579D02*
X1015184Y102592D01*
G01X1042014Y104618D02*
X1026600Y101900D01*
G01X1042014Y103297D02*
X1026600Y100579D01*
G01X1060521Y101354D02*
X1042014Y104618D01*
G01X1060521Y100033D02*
X1042014Y103297D01*
G01X1013365Y97928D02*
X1009475Y100652D01*
G01X1010409Y101586D02*
X1013875Y99159D01*
G01X1021201Y96547D02*
X1013365Y97928D01*
G01X1013875Y99159D02*
X1028980Y96496D01*
G01X1028994Y95173D02*
X1021201Y96547D01*
G01X1013875Y99159D02*
X1028980Y96496D01*
G01X1041500Y97674D02*
X1029000Y95174D01*
G01X1028980Y96496D02*
X1041500Y99000D01*
G01X1053775Y95219D02*
X1041500Y97674D01*
G01Y99000D02*
X1054000Y96500D01*
G01X1039111Y93035D02*
X1073142Y85802D01*
G01X1039111Y94365D02*
X1073142Y87132D01*
G01X1025675Y90179D02*
X1039111Y93035D01*
G01X1025675Y91509D02*
X1039111Y94365D01*
G01X1013693Y92726D02*
X1025675Y90179D01*
G01X1014222Y93943D02*
X1025675Y91509D01*
G01X1037994Y88885D02*
X1072531Y81544D01*
G01X1037994Y90215D02*
X1072531Y82874D01*
G01X1025170Y86159D02*
X1037994Y88885D01*
G01X1025170Y87489D02*
X1037994Y90215D01*
G01X1012323Y88889D02*
X1025170Y86159D01*
G01X1012852Y90106D02*
X1025170Y87489D01*
G01X1038851Y80241D02*
X1040465Y79898D01*
G01X1034254Y81218D02*
X1035868Y80875D01*
G01X1029657Y82195D02*
X1031271Y81852D01*
G01X1055225Y81705D02*
X1040465Y78568D01*
G01Y79898D02*
X1055225Y83035D01*
G01X1041500Y99000D02*
X1054000Y96500D01*
G01X1053775Y95219D02*
X1041500Y97674D01*
G01X1028980Y96496D02*
X1041500Y99000D01*
G01Y97674D02*
X1029000Y95174D01*
G01X1013875Y99159D02*
X1028980Y96496D01*
G01X1021201Y96547D02*
X1013365Y97928D01*
G01X1028994Y95173D02*
X1021201Y96547D01*
G01X1010409Y101586D02*
X1013875Y99159D01*
G01X1013365Y97928D02*
X1009475Y100652D01*
G01X1039111Y94365D02*
X1073142Y87132D01*
G01X1039111Y93035D02*
X1073142Y85802D01*
G01X1025675Y91509D02*
X1039111Y94365D01*
G01X1025675Y90179D02*
X1039111Y93035D01*
G01X1014222Y93943D02*
X1025675Y91509D01*
G01X1013693Y92726D02*
X1025675Y90179D01*
G01X1037994Y90215D02*
X1072531Y82874D01*
G01X1037994Y88885D02*
X1072531Y81544D01*
G01X1025170Y87489D02*
X1037994Y90215D01*
G01X1025170Y86159D02*
X1037994Y88885D01*
G01X1012852Y90106D02*
X1025170Y87489D01*
G01X1012323Y88889D02*
X1025170Y86159D01*
G01X1040465Y79898D02*
X1055225Y83035D01*
G01Y81705D02*
X1040465Y78568D01*
G01X1038851Y80241D02*
X1040465Y79898D01*
G01X1034254Y81218D02*
X1035868Y80875D01*
G01X1029657Y82195D02*
X1031271Y81852D01*
G01X1040089Y141372D02*
X1023000D01*
G01X1053253Y139051D02*
X1040089Y141372D01*
G01X1031475Y133472D02*
X1021600D01*
G01X1031589Y134772D02*
X1021533D01*
G01X1054561Y129401D02*
X1031475Y133472D01*
G01X1054561Y130722D02*
X1031589Y134772D01*
G01X1029770Y129678D02*
X1053971Y125411D01*
G01Y126732D02*
X1029884Y130978D01*
G01X1024893Y129678D02*
X1029770D01*
G01X1029884Y130978D02*
X1024893D01*
G01X1022328Y122028D02*
Y121029D01*
G01X1021028Y122567D02*
Y121029D01*
G01X1022616Y122316D02*
X1022328Y122028D01*
G01X1022077Y123616D02*
X1021028Y122567D01*
G01X1031648Y122316D02*
X1022616D01*
G01X1031762Y123616D02*
X1022077D01*
G01X1055480Y118113D02*
X1031648Y122316D01*
G01X1037060Y122682D02*
X1031762Y123616D01*
G01X1041689Y121866D02*
X1040064Y122152D01*
G01X1045926Y111900D02*
X1018800D01*
G01X1045812Y113200D02*
X1018874D01*
G01X1040089Y141372D02*
X1023000D01*
G01X1053253Y139051D02*
X1040089Y141372D01*
G01X1034476Y137439D02*
X1024703D01*
G01X1034580Y138739D02*
X1024703D01*
G01X1054356Y134259D02*
X1034476Y137439D01*
G01X1054345Y135578D02*
X1034580Y138739D01*
G01X1031589Y134772D02*
X1021533D01*
G01X1031475Y133472D02*
X1021600D01*
G01X1054561Y130722D02*
X1031589Y134772D01*
G01X1054561Y129401D02*
X1031475Y133472D01*
G01X1029884Y130978D02*
X1024893D01*
G01Y129678D02*
X1029770D01*
G01X1053971Y126732D02*
X1029884Y130978D01*
G01X1029770Y129678D02*
X1053971Y125411D01*
G01X1021028Y122567D02*
Y121029D01*
G01X1022328Y122028D02*
Y121029D01*
G01X1022077Y123616D02*
X1021028Y122567D01*
G01X1022616Y122316D02*
X1022328Y122028D01*
G01X1031762Y123616D02*
X1022077D01*
G01X1031648Y122316D02*
X1022616D01*
G01X1037060Y122682D02*
X1031762Y123616D01*
G01X1055480Y118113D02*
X1031648Y122316D01*
G01X1041689Y121866D02*
X1040064Y122152D01*
G01X1055480Y118113D02*
X1031648Y122316D01*
G01X1055480Y118113D02*
X1031648Y122316D01*
G01X1045812Y113200D02*
X1018874D01*
G01X1045926Y111900D02*
X1018800D01*
G01X1034580Y138739D02*
X1024703D01*
G01X1034476Y137439D02*
X1024703D01*
G01X1054345Y135578D02*
X1034580Y138739D01*
G01X1054356Y134259D02*
X1034476Y137439D01*
G01X1010300Y108623D02*
Y111530D01*
G01X1011600Y108737D02*
Y111530D01*
G01Y108737D02*
Y111530D01*
G01X1010300Y108623D02*
Y111530D01*
G01X1037680Y174520D02*
X1055158Y177602D01*
G01X1026031Y176574D02*
X1037680Y174520D01*
G01X1037778Y171576D02*
X1054680Y174556D01*
G01X1037778Y170255D02*
X1055190Y173325D01*
G01X1024600Y173900D02*
X1037778Y171576D01*
G01X1024486Y172600D02*
X1037778Y170255D01*
G01X1022600Y173900D02*
X1024600D01*
G01X1022500Y172600D02*
X1024486D01*
G01X1026145Y170000D02*
X1023731D01*
G01X1026031Y168700D02*
X1023192D01*
G01X1038078Y167896D02*
X1026145Y170000D01*
G01X1038078Y166575D02*
X1026031Y168700D01*
G01X1056990Y171231D02*
X1038078Y167896D01*
G01X1057500Y170000D02*
X1038078Y166575D01*
G01X1036486Y158973D02*
X1050635Y156477D01*
G01Y157798D02*
X1036600Y160273D01*
G01X1021800Y158973D02*
X1036486D01*
G01X1036600Y160273D02*
X1021800D01*
G01X1017459Y153974D02*
Y154336D01*
G01X1018759Y154188D02*
Y154032D01*
G01X1018114Y152448D02*
G02X1017460Y153974I1585J1582D01*
G01X1019034Y153368D02*
G03X1019424Y153134I664J664D01*
G01X1018759Y154032D02*
G03X1019034Y153368I939J0D01*
G01X1019044Y151890D02*
G02X1018114Y152448I653J2142D01*
G01X1019424Y153134D02*
G03X1019698Y153093I274J898D01*
G01X1019034Y153368D02*
G03X1019424Y153134I664J664D01*
G01X1018759Y154032D02*
G03X1019034Y153368I939J0D01*
G01X1019695Y151793D02*
G02X1019044Y151890I0J2232D01*
G01X1019424Y153134D02*
G03X1019698Y153093I274J898D01*
G01X1019034Y153368D02*
G03X1019424Y153134I664J664D01*
G01X1020101Y151793D02*
X1019695D01*
G01X1019698Y153093D02*
X1020100D01*
G01X1021620Y152422D02*
G02X1020101Y151793I-1520J1523D01*
G01X1020100Y153093D02*
G03X1020702Y153343I-1J852D01*
G01X1023546Y154348D02*
X1021620Y152422D01*
G01X1020702Y153343D02*
X1023007Y155648D01*
G01X1038186Y154348D02*
X1023546D01*
G01X1023007Y155648D02*
X1038300D01*
G01X1051551Y151990D02*
X1038186Y154348D01*
G01X1038300Y155648D02*
X1051551Y153311D01*
G01X1041083Y149219D02*
X1022719D01*
G01X1041197Y150519D02*
X1022580D01*
G01X1051400Y147400D02*
X1041083Y149219D01*
G01X1051400Y148721D02*
X1041197Y150519D01*
G01X1040291Y145600D02*
X1052165Y143507D01*
G01X1040405Y146900D02*
X1052167Y144828D01*
G01X1024600Y145600D02*
X1040291D01*
G01X1024600Y146900D02*
X1040405D01*
G01X1022552Y144751D02*
G02X1024600Y145600I2049J-2048D01*
G01X1021629Y145670D02*
G02X1024600Y146900I2970J-2971D01*
G01X1020614Y143919D02*
G03X1022500Y144700I0J2667D01*
G01X1020614Y145219D02*
G03X1021580Y145620I-1J1366D01*
G01X1019695Y143919D02*
X1020614D01*
G01X1019698Y145219D02*
X1020614D01*
G01X1019044Y144016D02*
G03X1019695Y143919I651J2135D01*
G01X1019424Y145260D02*
G03X1019698Y145219I274J898D01*
G01X1019034Y145494D02*
G03X1019424Y145260I664J664D01*
G01X1018114Y144574D02*
G03X1019044Y144016I1583J1584D01*
G01X1019424Y145260D02*
G03X1019698Y145219I274J898D01*
G01X1019034Y145494D02*
G03X1019424Y145260I664J664D01*
G01X1018759Y146158D02*
G03X1019034Y145494I939J0D01*
G01X1017460Y146100D02*
G03X1018114Y144574I2239J56D01*
G01X1019034Y145494D02*
G03X1019424Y145260I664J664D01*
G01X1018759Y146158D02*
G03X1019034Y145494I939J0D01*
G01X1017459Y146462D02*
Y146100D01*
G01X1018759Y146314D02*
Y146158D01*
G01X1037680Y174520D02*
X1055158Y177602D01*
G01X1026031Y176574D02*
X1037680Y174520D01*
G01X1037778Y170255D02*
X1055190Y173325D01*
G01X1037778Y171576D02*
X1054680Y174556D01*
G01X1024486Y172600D02*
X1037778Y170255D01*
G01X1024600Y173900D02*
X1037778Y171576D01*
G01X1022500Y172600D02*
X1024486D01*
G01X1022600Y173900D02*
X1024600D01*
G01X1026031Y168700D02*
X1023192D01*
G01X1026145Y170000D02*
X1023731D01*
G01X1038078Y166575D02*
X1026031Y168700D01*
G01X1038078Y167896D02*
X1026145Y170000D01*
G01X1057500D02*
X1038078Y166575D01*
G01X1056990Y171231D02*
X1038078Y167896D01*
G01X1036600Y160273D02*
X1021800D01*
G01Y158973D02*
X1036486D01*
G01X1050635Y157798D02*
X1036600Y160273D01*
G01X1036486Y158973D02*
X1050635Y156477D01*
G01X1038300Y155648D02*
X1051551Y153311D01*
G01Y151990D02*
X1038186Y154348D01*
G01X1023007Y155648D02*
X1038300D01*
G01X1038186Y154348D02*
X1023546D01*
G01X1020702Y153343D02*
X1023007Y155648D01*
G01X1023546Y154348D02*
X1021620Y152422D01*
G01X1020100Y153093D02*
G03X1020702Y153343I-1J852D01*
G01X1021620Y152422D02*
G02X1020101Y151793I-1520J1523D01*
G01X1019698Y153093D02*
X1020100D01*
G01X1020101Y151793D02*
X1019695D01*
G01X1019424Y153134D02*
G03X1019698Y153093I274J898D01*
G01X1019044Y151890D02*
G02X1018114Y152448I653J2142D01*
G01X1019695Y151793D02*
G02X1019044Y151890I0J2232D01*
G01X1019034Y153368D02*
G03X1019424Y153134I664J664D01*
G01X1018114Y152448D02*
G02X1017460Y153974I1585J1582D01*
G01X1019044Y151890D02*
G02X1018114Y152448I653J2142D01*
G01X1019695Y151793D02*
G02X1019044Y151890I0J2232D01*
G01X1018759Y154032D02*
G03X1019034Y153368I939J0D01*
G01X1018114Y152448D02*
G02X1017460Y153974I1585J1582D01*
G01X1019044Y151890D02*
G02X1018114Y152448I653J2142D01*
G01X1018759Y154188D02*
Y154032D01*
G01X1017459Y153974D02*
Y154336D01*
G01X1041197Y150519D02*
X1022580D01*
G01X1041083Y149219D02*
X1022719D01*
G01X1051400Y148721D02*
X1041197Y150519D01*
G01X1051400Y147400D02*
X1041083Y149219D01*
G01X1040405Y146900D02*
X1052167Y144828D01*
G01X1040291Y145600D02*
X1052165Y143507D01*
G01X1024600Y146900D02*
X1040405D01*
G01X1024600Y145600D02*
X1040291D01*
G01X1021629Y145670D02*
G02X1024600Y146900I2970J-2971D01*
G01X1022552Y144751D02*
G02X1024600Y145600I2049J-2048D01*
G01X1020614Y145219D02*
G03X1021580Y145620I-1J1366D01*
G01X1020614Y143919D02*
G03X1022500Y144700I0J2667D01*
G01X1019698Y145219D02*
X1020614D01*
G01X1019695Y143919D02*
X1020614D01*
G01X1019424Y145260D02*
G03X1019698Y145219I274J898D01*
G01X1019044Y144016D02*
G03X1019695Y143919I651J2135D01*
G01X1018114Y144574D02*
G03X1019044Y144016I1583J1584D01*
G01X1019034Y145494D02*
G03X1019424Y145260I664J664D01*
G01X1019044Y144016D02*
G03X1019695Y143919I651J2135D01*
G01X1018114Y144574D02*
G03X1019044Y144016I1583J1584D01*
G01X1017460Y146100D02*
G03X1018114Y144574I2239J56D01*
G01X1018759Y146158D02*
G03X1019034Y145494I939J0D01*
G01X1018114Y144574D02*
G03X1019044Y144016I1583J1584D01*
G01X1017460Y146100D02*
G03X1018114Y144574I2239J56D01*
G01X1018759Y146314D02*
Y146158D01*
G01X1017459Y146462D02*
Y146100D01*
G01X1040203Y142672D02*
X1023100D01*
G01X1053253Y140372D02*
X1040203Y142672D01*
G01D02*
X1023100D01*
G01X1053253Y140372D02*
X1040203Y142672D01*
G01X1038008Y207381D02*
X1045579Y208716D01*
G01X1038008Y206060D02*
X1046089Y207485D01*
G01X1026731Y209369D02*
X1038008Y207381D01*
G01X1026617Y208069D02*
X1038008Y206060D01*
G01X1023192Y208069D02*
X1026617D01*
G01X1027875Y201458D02*
X1022600D01*
G01X1027797Y200158D02*
X1022600D01*
G01X1042340Y199732D02*
X1027875Y201458D01*
G01X1042679Y198382D02*
X1027797Y200158D01*
G01X1044541Y201273D02*
X1042340Y199732D01*
G01X1026145Y197558D02*
X1023731D01*
G01X1023192Y196258D02*
X1026031D01*
G01X1040136Y195092D02*
X1026145Y197558D01*
G01X1026031Y196258D02*
X1040136Y193771D01*
G01X1045665Y196067D02*
X1040136Y195092D01*
G01Y193771D02*
X1046175Y194836D01*
G01X1024600Y193584D02*
X1022600D01*
G01X1024486Y192284D02*
X1022600D01*
G01X1041050Y190684D02*
X1024600Y193584D01*
G01X1041050Y189363D02*
X1024486Y192284D01*
G01X1046990Y191731D02*
X1041050Y190684D01*
G01X1047500Y190500D02*
X1041050Y189363D01*
G01X1037220Y184922D02*
X1050057Y187184D01*
G01X1037445Y183641D02*
X1050282Y185903D01*
G01X1037030Y184922D02*
G03X1037220I95J542D01*
G01X1036805Y183641D02*
G03X1037445I320J1823D01*
G01X1020707Y187800D02*
X1037030Y184922D01*
G01X1020609Y186497D02*
X1036805Y183641D01*
G01X1018580Y186919D02*
G02X1020707Y187800I2127J-2127D01*
G01X1019500Y186000D02*
G02X1020609Y186497I1207J-1207D01*
G01X1018043Y186382D02*
X1018580Y186919D01*
G01X1019007Y185507D02*
X1019500Y186000D01*
G01X1037616Y179480D02*
X1049828Y181633D01*
G01X1037616Y178159D02*
X1050338Y180402D01*
G01X1024600Y181774D02*
X1037616Y179480D01*
G01X1024483Y180474D02*
X1037616Y178159D01*
G01X1022600Y181774D02*
X1024600D01*
G01X1022600Y180474D02*
X1024483D01*
G01X1038008Y206060D02*
X1046089Y207485D01*
G01X1038008Y207381D02*
X1045579Y208716D01*
G01X1026617Y208069D02*
X1038008Y206060D01*
G01X1026731Y209369D02*
X1038008Y207381D01*
G01X1023192Y208069D02*
X1026617D01*
G01X1027797Y200158D02*
X1022600D01*
G01X1027875Y201458D02*
X1022600D01*
G01X1042679Y198382D02*
X1027797Y200158D01*
G01X1042340Y199732D02*
X1027875Y201458D01*
G01X1044541Y201273D02*
X1042340Y199732D01*
G01X1040136Y193771D02*
X1046175Y194836D01*
G01X1045665Y196067D02*
X1040136Y195092D01*
G01X1026031Y196258D02*
X1040136Y193771D01*
G01Y195092D02*
X1026145Y197558D01*
G01X1023192Y196258D02*
X1026031D01*
G01X1026145Y197558D02*
X1023731D01*
G01X1024486Y192284D02*
X1022600D01*
G01X1024600Y193584D02*
X1022600D01*
G01X1041050Y189363D02*
X1024486Y192284D01*
G01X1041050Y190684D02*
X1024600Y193584D01*
G01X1047500Y190500D02*
X1041050Y189363D01*
G01X1046990Y191731D02*
X1041050Y190684D01*
G01X1037445Y183641D02*
X1050282Y185903D01*
G01X1037220Y184922D02*
X1050057Y187184D01*
G01X1036805Y183641D02*
G03X1037445I320J1823D01*
G01X1037030Y184922D02*
G03X1037220I95J542D01*
G01X1020609Y186497D02*
X1036805Y183641D01*
G01X1020707Y187800D02*
X1037030Y184922D01*
G01X1019500Y186000D02*
G02X1020609Y186497I1207J-1207D01*
G01X1018580Y186919D02*
G02X1020707Y187800I2127J-2127D01*
G01X1019007Y185507D02*
X1019500Y186000D01*
G01X1018043Y186382D02*
X1018580Y186919D01*
G01X1037616Y178159D02*
X1050338Y180402D01*
G01X1037616Y179480D02*
X1049828Y181633D01*
G01X1024483Y180474D02*
X1037616Y178159D01*
G01X1024600Y181774D02*
X1037616Y179480D01*
G01X1022600Y180474D02*
X1024483D01*
G01X1022600Y181774D02*
X1024600D01*
G01X1037680Y175841D02*
X1054648Y178833D01*
G01X1026145Y177874D02*
X1037680Y175841D01*
G01X1023731Y177874D02*
X1026145D01*
G01X1023192Y176574D02*
X1026031D01*
G01X1037680Y175841D02*
X1054648Y178833D01*
G01X1026145Y177874D02*
X1037680Y175841D01*
G01X1023192Y176574D02*
X1026031D01*
G01X1023731Y177874D02*
X1026145D01*
G01X1022600Y236891D02*
X1036592Y246690D01*
G01X1024060Y236326D02*
X1037526Y245756D01*
G01X1038726Y239178D02*
X1052509Y258863D01*
G01X1039660Y238244D02*
X1053740Y258353D01*
G01X1030460Y233390D02*
X1038726Y239178D01*
G01X1035339Y235219D02*
X1039660Y238244D01*
G01X1030970Y232159D02*
X1035339Y235219D01*
G01X1028250Y233000D02*
X1030460Y233390D01*
G01X1028364Y231700D02*
X1030970Y232159D01*
G01X1023680Y233000D02*
X1028250D01*
G01X1023681Y231700D02*
X1028364D01*
G01X1023407Y233091D02*
G03X1023680Y233000I272J362D01*
G01X1022627Y232051D02*
G03X1023681Y231700I1052J1402D01*
G01X1034996Y230360D02*
X1044138Y236761D01*
G01X1040314Y232496D02*
X1045072Y235827D01*
G01X1035506Y229129D02*
X1040314Y232496D01*
G01X1027386Y229017D02*
X1034996Y230360D01*
G01X1027500Y227717D02*
X1035506Y229129D01*
G01X1022600Y229017D02*
X1027386D01*
G01X1022600Y227717D02*
X1027500D01*
G01X1037035Y226975D02*
X1047372Y234213D01*
G01X1037545Y225744D02*
X1042950Y229529D01*
G01X1026503Y225117D02*
X1037035Y226975D01*
G01X1026617Y223817D02*
X1037545Y225744D01*
G01X1023731Y225117D02*
X1026503D01*
G01X1023192Y223817D02*
X1026617D01*
G01X1030333Y221143D02*
X1022600D01*
G01X1030219Y219843D02*
X1022600D01*
G01X1035000Y220321D02*
X1030333Y221143D01*
G01X1035000Y219000D02*
X1030219Y219843D01*
G01X1039852Y221176D02*
X1035000Y220321D01*
G01X1040362Y219945D02*
X1035000Y219000D01*
G01X1050150Y228386D02*
X1039852Y221176D01*
G01X1051084Y227452D02*
X1040362Y219945D01*
G01X1040266Y215831D02*
X1055884Y226767D01*
G01X1040776Y214600D02*
X1056818Y225833D01*
G01X1038887Y215588D02*
X1040266Y215831D01*
G01X1037504Y214023D02*
X1040776Y214600D01*
G01X1037504Y215344D02*
X1038887Y215588D01*
G01X1037504Y214023D02*
X1040776Y214600D01*
G01X1026731Y217243D02*
X1037504Y215344D01*
G01X1026617Y215943D02*
X1037504Y214023D01*
G01X1023731Y217243D02*
X1026731D01*
G01X1023192Y215943D02*
X1026617D01*
G01X1042267Y212662D02*
X1059540Y224757D01*
G01X1037500Y211821D02*
X1042267Y212662D01*
G01X1037500Y210500D02*
X1042777Y211431D01*
G01X1029282Y213269D02*
X1037500Y211821D01*
G01X1029168Y211969D02*
X1037500Y210500D01*
G01X1022600Y213269D02*
X1029282D01*
G01X1022600Y211969D02*
X1029168D01*
G01X1024060Y236326D02*
X1037526Y245756D01*
G01X1022600Y236891D02*
X1036592Y246690D01*
G01X1039660Y238244D02*
X1053740Y258353D01*
G01X1038726Y239178D02*
X1052509Y258863D01*
G01X1035339Y235219D02*
X1039660Y238244D01*
G01X1030460Y233390D02*
X1038726Y239178D01*
G01X1030970Y232159D02*
X1035339Y235219D01*
G01X1030460Y233390D02*
X1038726Y239178D01*
G01X1028364Y231700D02*
X1030970Y232159D01*
G01X1028250Y233000D02*
X1030460Y233390D01*
G01X1023681Y231700D02*
X1028364D01*
G01X1023680Y233000D02*
X1028250D01*
G01X1022627Y232051D02*
G03X1023681Y231700I1052J1402D01*
G01X1023407Y233091D02*
G03X1023680Y233000I272J362D01*
G01X1040314Y232496D02*
X1045072Y235827D01*
G01X1034996Y230360D02*
X1044138Y236761D01*
G01X1035506Y229129D02*
X1040314Y232496D01*
G01X1034996Y230360D02*
X1044138Y236761D01*
G01X1027500Y227717D02*
X1035506Y229129D01*
G01X1027386Y229017D02*
X1034996Y230360D01*
G01X1022600Y227717D02*
X1027500D01*
G01X1022600Y229017D02*
X1027386D01*
G01X1037035Y226975D02*
X1047372Y234213D01*
G01X1037545Y225744D02*
X1042950Y229529D01*
G01X1037035Y226975D02*
X1047372Y234213D01*
G01X1026617Y223817D02*
X1037545Y225744D01*
G01X1026503Y225117D02*
X1037035Y226975D01*
G01X1023192Y223817D02*
X1026617D01*
G01X1023731Y225117D02*
X1026503D01*
G01X1030219Y219843D02*
X1022600D01*
G01X1030333Y221143D02*
X1022600D01*
G01X1035000Y219000D02*
X1030219Y219843D01*
G01X1035000Y220321D02*
X1030333Y221143D01*
G01X1040362Y219945D02*
X1035000Y219000D01*
G01X1039852Y221176D02*
X1035000Y220321D01*
G01X1051084Y227452D02*
X1040362Y219945D01*
G01X1050150Y228386D02*
X1039852Y221176D01*
G01X1040776Y214600D02*
X1056818Y225833D01*
G01X1040266Y215831D02*
X1055884Y226767D01*
G01X1037504Y214023D02*
X1040776Y214600D01*
G01X1038887Y215588D02*
X1040266Y215831D01*
G01X1037504Y215344D02*
X1038887Y215588D01*
G01X1026617Y215943D02*
X1037504Y214023D01*
G01X1026731Y217243D02*
X1037504Y215344D01*
G01X1023192Y215943D02*
X1026617D01*
G01X1023731Y217243D02*
X1026731D01*
G01X1042267Y212662D02*
X1059540Y224757D01*
G01X1037500Y210500D02*
X1042777Y211431D01*
G01X1037500Y211821D02*
X1042267Y212662D01*
G01X1029168Y211969D02*
X1037500Y210500D01*
G01X1029282Y213269D02*
X1037500Y211821D01*
G01X1022600Y211969D02*
X1029168D01*
G01X1022600Y213269D02*
X1029282D01*
G01X1023731Y209369D02*
X1026731D01*
G01X1023731D02*
X1026731D01*
G01X1010723Y274342D02*
X1039096Y314864D01*
G01X1011954Y273832D02*
X1040327Y314354D01*
G01X1010078Y270685D02*
X1010723Y274342D01*
G01X1011359Y270459D02*
X1011954Y273832D01*
G01X1009500Y267398D02*
X1010078Y270685D01*
G01X1011079Y268871D02*
X1011359Y270459D01*
G01X1010800Y267284D02*
X1011079Y268871D01*
G01X1009500Y263600D02*
Y267398D01*
G01X1010800Y263600D02*
Y267284D01*
G01X1014200Y271375D02*
X1045750Y316434D01*
G01X1015431Y270865D02*
X1046981Y315924D01*
G01X1013500Y267399D02*
X1014200Y271375D01*
G01X1014800Y267285D02*
X1015431Y270865D01*
G01X1013500Y263500D02*
Y267399D01*
G01X1014800Y263500D02*
Y267285D01*
G01X1011954Y273832D02*
X1040327Y314354D01*
G01X1010723Y274342D02*
X1039096Y314864D01*
G01X1011359Y270459D02*
X1011954Y273832D01*
G01X1010078Y270685D02*
X1010723Y274342D01*
G01X1011079Y268871D02*
X1011359Y270459D01*
G01X1009500Y267398D02*
X1010078Y270685D01*
G01X1010800Y267284D02*
X1011079Y268871D01*
G01X1009500Y267398D02*
X1010078Y270685D01*
G01X1010800Y263600D02*
Y267284D01*
G01X1009500Y263600D02*
Y267398D01*
G01X1015431Y270865D02*
X1046981Y315924D01*
G01X1014200Y271375D02*
X1045750Y316434D01*
G01X1014800Y267285D02*
X1015431Y270865D01*
G01X1013500Y267399D02*
X1014200Y271375D01*
G01X1014800Y263500D02*
Y267285D01*
G01X1013500Y263500D02*
Y267399D01*
G01X1036592Y246690D02*
X1046269Y260510D01*
G01X1037526Y245756D02*
X1047500Y260000D01*
G01X1037526Y245756D02*
X1047500Y260000D01*
G01X1036592Y246690D02*
X1046269Y260510D01*
G01X1039096Y314864D02*
X1106983Y699871D01*
G01X1040327Y314354D02*
X1074321Y507143D01*
G01X1039096Y314864D02*
X1106983Y699871D01*
G01X1040327Y314354D02*
X1074321Y507143D01*
G01X1039096Y314864D02*
X1106983Y699871D01*
G01X1009410Y404708D02*
Y402955D01*
G01X1010710Y404822D02*
Y402841D01*
G01Y404822D02*
Y402841D01*
G01X1009410Y404708D02*
Y402955D01*
G01X1057818Y630490D02*
X1036569Y751001D01*
G01X1059139Y630490D02*
X1037890Y751001D01*
G01X1059139Y630490D02*
X1037890Y751001D01*
G01X1057818Y630490D02*
X1036569Y751001D01*
G01D02*
X1046179Y805500D01*
G01X1037890Y751001D02*
X1042655Y778025D01*
G01X1036569Y751001D02*
X1046179Y805500D01*
G01X1037890Y751001D02*
X1042655Y778025D01*
G01X1036569Y751001D02*
X1046179Y805500D01*
G01X1066249Y71928D02*
X1065381Y76013D01*
G01X1066603Y76519D02*
X1067579Y71928D01*
G01X1064398Y63226D02*
X1066249Y71928D01*
G01X1067579D02*
X1065728Y63226D01*
G01X1065071Y60064D02*
X1064398Y63226D01*
G01X1065728D02*
X1066284Y60611D01*
G01X1065893Y59266D02*
G02X1065076Y60057I1301J2161D01*
G01X1066284Y60611D02*
G03X1066564Y60381I907J818D01*
G01X1067947Y58031D02*
X1065893Y59266D01*
G01X1066564Y60381D02*
X1068308Y59331D01*
G01X1069699Y58031D02*
X1067947D01*
G01X1068308Y59331D02*
X1070037D01*
G01X1057899Y62371D02*
X1053800Y65033D01*
G01X1058839Y63311D02*
X1054306Y66255D01*
G01X1060266Y58721D02*
X1057899Y62371D01*
G01X1061622Y59020D02*
X1058839Y63311D01*
G01X1060013Y56946D02*
X1060266Y58721D01*
G01X1061226Y56237D02*
X1061622Y59020D01*
G01X1059487Y56541D02*
X1060013Y56946D01*
G01X1059932Y55241D02*
X1061226Y56237D01*
G01X1058159Y56541D02*
X1059487D01*
G01X1059932Y55241D02*
X1061226Y56237D01*
G01X1058353Y55241D02*
X1059932D01*
G01X1068308Y59331D02*
X1070037D01*
G01X1069699Y58031D02*
X1067947D01*
G01X1066564Y60381D02*
X1068308Y59331D01*
G01X1067947Y58031D02*
X1065893Y59266D01*
G01X1066284Y60611D02*
G03X1066564Y60381I907J818D01*
G01X1065893Y59266D02*
G02X1065076Y60057I1301J2161D01*
G01X1065728Y63226D02*
X1066284Y60611D01*
G01X1065071Y60064D02*
X1064398Y63226D01*
G01X1067579Y71928D02*
X1065728Y63226D01*
G01X1064398D02*
X1066249Y71928D01*
G01X1066603Y76519D02*
X1067579Y71928D01*
G01X1066249D02*
X1065381Y76013D01*
G01X1058839Y63311D02*
X1054306Y66255D01*
G01X1057899Y62371D02*
X1053800Y65033D01*
G01X1061622Y59020D02*
X1058839Y63311D01*
G01X1060266Y58721D02*
X1057899Y62371D01*
G01X1061226Y56237D02*
X1061622Y59020D01*
G01X1060013Y56946D02*
X1060266Y58721D01*
G01X1059932Y55241D02*
X1061226Y56237D01*
G01X1059487Y56541D02*
X1060013Y56946D01*
G01X1058159Y56541D02*
X1059487D01*
G01X1058353Y55241D02*
X1059932D01*
G01X1058159Y56541D02*
X1059487D01*
G01X1085110Y104369D02*
X1060521Y100033D01*
G01X1084600Y105600D02*
X1060521Y101354D01*
G01X1084600Y105600D02*
X1060521Y101354D01*
G01X1085110Y104369D02*
X1060521Y100033D01*
G01X1058467Y94391D02*
X1053775Y95219D01*
G01X1054000Y96500D02*
X1058467Y95712D01*
G01X1087216Y99461D02*
X1058467Y94391D01*
G01Y95712D02*
X1086706Y100692D01*
G01X1073142Y85802D02*
X1078396Y86919D01*
G01X1073142Y87132D02*
X1077890Y88141D01*
G01X1072531Y81544D02*
X1082957Y83761D01*
G01X1072531Y82874D02*
X1082451Y84983D01*
G01X1059971Y80696D02*
X1055225Y81705D01*
G01Y83035D02*
X1060477Y81918D01*
G01X1064067Y78036D02*
X1059971Y80696D01*
G01X1060477Y81918D02*
X1065007Y78976D01*
G01X1065381Y76013D02*
X1064067Y78036D01*
G01X1065007Y78976D02*
X1066603Y76519D01*
G01X1058467Y95712D02*
X1086706Y100692D01*
G01X1087216Y99461D02*
X1058467Y94391D01*
G01X1054000Y96500D02*
X1058467Y95712D01*
G01Y94391D02*
X1053775Y95219D01*
G01X1073142Y87132D02*
X1077890Y88141D01*
G01X1073142Y85802D02*
X1078396Y86919D01*
G01X1072531Y82874D02*
X1082451Y84983D01*
G01X1072531Y81544D02*
X1082957Y83761D01*
G01X1065007Y78976D02*
X1066603Y76519D01*
G01X1065381Y76013D02*
X1064067Y78036D01*
G01X1060477Y81918D02*
X1065007Y78976D01*
G01X1064067Y78036D02*
X1059971Y80696D01*
G01X1055225Y83035D02*
X1060477Y81918D01*
G01X1059971Y80696D02*
X1055225Y81705D01*
G01X1071000Y143500D02*
X1053253Y140372D01*
G01X1071510Y142269D02*
X1053253Y139051D01*
G01X1073767Y132787D02*
X1054561Y129401D01*
G01X1073257Y134018D02*
X1054561Y130722D01*
G01X1089189Y143586D02*
X1073767Y132787D01*
G01X1088255Y144520D02*
X1073257Y134018D01*
G01X1053971Y125411D02*
X1077233Y129513D01*
G01X1076723Y130744D02*
X1053971Y126732D01*
G01X1055480Y119434D02*
X1044693Y121336D01*
G01X1077381Y121975D02*
X1055480Y118113D01*
G01X1076871Y123206D02*
X1055480Y119434D01*
G01X1079201Y117768D02*
X1045926Y111900D01*
G01X1078691Y118999D02*
X1045812Y113200D01*
G01X1071510Y142269D02*
X1053253Y139051D01*
G01X1071000Y143500D02*
X1053253Y140372D01*
G01X1072666Y137488D02*
X1054356Y134259D01*
G01X1072156Y138719D02*
X1054345Y135578D01*
G01X1084868Y146033D02*
X1072666Y137488D01*
G01X1083935Y146967D02*
X1072156Y138719D01*
G01X1073257Y134018D02*
X1054561Y130722D01*
G01X1073767Y132787D02*
X1054561Y129401D01*
G01X1088255Y144520D02*
X1073257Y134018D01*
G01X1089189Y143586D02*
X1073767Y132787D01*
G01X1076723Y130744D02*
X1053971Y126732D01*
G01Y125411D02*
X1077233Y129513D01*
G01X1055480Y119434D02*
X1044693Y121336D01*
G01X1076871Y123206D02*
X1055480Y119434D01*
G01X1077381Y121975D02*
X1055480Y118113D01*
G01X1078691Y118999D02*
X1045812Y113200D01*
G01X1079201Y117768D02*
X1045926Y111900D01*
G01X1072156Y138719D02*
X1054345Y135578D01*
G01X1072666Y137488D02*
X1054356Y134259D01*
G01X1083935Y146967D02*
X1072156Y138719D01*
G01X1084868Y146033D02*
X1072666Y137488D01*
G01X1054680Y174556D02*
X1086554Y196875D01*
G01X1055190Y173325D02*
X1071364Y184651D01*
G01X1087937Y192899D02*
X1056990Y171231D01*
G01X1073210Y181000D02*
X1057500Y170000D01*
G01X1074406Y171283D02*
X1102902Y191235D01*
G01X1102392Y192466D02*
X1073472Y172217D01*
G01X1068864Y163367D02*
X1074406Y171283D01*
G01X1073472Y172217D02*
X1067930Y164301D01*
G01X1061848Y158454D02*
X1068864Y163367D01*
G01X1067930Y164301D02*
X1061338Y159685D01*
G01X1050635Y156477D02*
X1061848Y158454D01*
G01X1061338Y159685D02*
X1050635Y157798D01*
G01X1063910Y154169D02*
X1051551Y151990D01*
G01Y153311D02*
X1063400Y155400D01*
G01X1072541Y160213D02*
X1063910Y154169D01*
G01X1063400Y155400D02*
X1071607Y161147D01*
G01X1078468Y168678D02*
X1072541Y160213D01*
G01X1071607Y161147D02*
X1077534Y169612D01*
G01X1065462Y149879D02*
X1051400Y147400D01*
G01X1064950Y151109D02*
X1051400Y148721D01*
G01X1075725Y157065D02*
X1065462Y149879D01*
G01X1074791Y157999D02*
X1064950Y151109D01*
G01X1080732Y164216D02*
X1075725Y157065D01*
G01X1079798Y165150D02*
X1074791Y157999D01*
G01X1067654Y146238D02*
X1079190Y154315D01*
G01X1067144Y147469D02*
X1078256Y155249D01*
G01X1052165Y143507D02*
X1067654Y146238D01*
G01X1052167Y144828D02*
X1067144Y147469D01*
G01X1054680Y174556D02*
X1086554Y196875D01*
G01X1055190Y173325D02*
X1071364Y184651D01*
G01X1054680Y174556D02*
X1086554Y196875D01*
G01X1073210Y181000D02*
X1057500Y170000D01*
G01X1087937Y192899D02*
X1056990Y171231D01*
G01X1087937Y192899D02*
X1056990Y171231D01*
G01X1061338Y159685D02*
X1050635Y157798D01*
G01Y156477D02*
X1061848Y158454D01*
G01X1067930Y164301D02*
X1061338Y159685D01*
G01X1061848Y158454D02*
X1068864Y163367D01*
G01X1073472Y172217D02*
X1067930Y164301D01*
G01X1068864Y163367D02*
X1074406Y171283D01*
G01X1102392Y192466D02*
X1073472Y172217D01*
G01X1074406Y171283D02*
X1102902Y191235D01*
G01X1071607Y161147D02*
X1077534Y169612D01*
G01X1078468Y168678D02*
X1072541Y160213D01*
G01X1063400Y155400D02*
X1071607Y161147D01*
G01X1072541Y160213D02*
X1063910Y154169D01*
G01X1051551Y153311D02*
X1063400Y155400D01*
G01X1063910Y154169D02*
X1051551Y151990D01*
G01X1064950Y151109D02*
X1051400Y148721D01*
G01X1065462Y149879D02*
X1051400Y147400D01*
G01X1074791Y157999D02*
X1064950Y151109D01*
G01X1075725Y157065D02*
X1065462Y149879D01*
G01X1079798Y165150D02*
X1074791Y157999D01*
G01X1080732Y164216D02*
X1075725Y157065D01*
G01X1067144Y147469D02*
X1078256Y155249D01*
G01X1067654Y146238D02*
X1079190Y154315D01*
G01X1052167Y144828D02*
X1067144Y147469D01*
G01X1052165Y143507D02*
X1067654Y146238D01*
G01X1081143Y150602D02*
X1071000Y143500D01*
G01X1082077Y149668D02*
X1071510Y142269D01*
G01X1082077Y149668D02*
X1071510Y142269D01*
G01X1081143Y150602D02*
X1071000Y143500D01*
G01X1045579Y208716D02*
X1064584Y222023D01*
G01X1046089Y207485D02*
X1055828Y214305D01*
G01X1045288Y200209D02*
X1042852Y198503D01*
G01X1068259Y218005D02*
X1044541Y201273D01*
G01X1069194Y217073D02*
X1045288Y200209D01*
G01X1071909Y214443D02*
X1045665Y196067D01*
G01X1059533Y204190D02*
X1072843Y213509D01*
G01X1046175Y194836D02*
X1059533Y204190D01*
G01X1074019Y210656D02*
X1046990Y191731D01*
G01X1074953Y209722D02*
X1047500Y190500D01*
G01X1050276Y187275D02*
X1079460Y207709D01*
G01X1051022Y186209D02*
X1080206Y206644D01*
G01X1050057Y187184D02*
G03X1050276Y187275I-96J541D01*
G01X1050282Y185903D02*
G03X1051022Y186209I-320J1822D01*
G01X1049828Y181633D02*
X1083810Y205428D01*
G01X1050338Y180402D02*
X1084744Y204494D01*
G01X1045579Y208716D02*
X1064584Y222023D01*
G01X1046089Y207485D02*
X1055828Y214305D01*
G01X1045579Y208716D02*
X1064584Y222023D01*
G01X1045288Y200209D02*
X1042852Y198503D01*
G01X1069194Y217073D02*
X1045288Y200209D01*
G01X1068259Y218005D02*
X1044541Y201273D01*
G01X1059533Y204190D02*
X1072843Y213509D01*
G01X1071909Y214443D02*
X1045665Y196067D01*
G01X1046175Y194836D02*
X1059533Y204190D01*
G01X1071909Y214443D02*
X1045665Y196067D01*
G01X1074953Y209722D02*
X1047500Y190500D01*
G01X1074019Y210656D02*
X1046990Y191731D01*
G01X1051022Y186209D02*
X1080206Y206644D01*
G01X1050276Y187275D02*
X1079460Y207709D01*
G01X1050282Y185903D02*
G03X1051022Y186209I-320J1822D01*
G01X1050057Y187184D02*
G03X1050276Y187275I-96J541D01*
G01X1050338Y180402D02*
X1084744Y204494D01*
G01X1049828Y181633D02*
X1083810Y205428D01*
G01X1054648Y178833D02*
X1084772Y199926D01*
G01X1070457Y188315D02*
X1085706Y198992D01*
G01X1055158Y177602D02*
X1070457Y188315D01*
G01X1071364Y184651D02*
X1087488Y195941D01*
G01X1088871Y191965D02*
X1073210Y181000D01*
G01X1070457Y188315D02*
X1085706Y198992D01*
G01X1054648Y178833D02*
X1084772Y199926D01*
G01X1055158Y177602D02*
X1070457Y188315D01*
G01X1054648Y178833D02*
X1084772Y199926D01*
G01X1071364Y184651D02*
X1087488Y195941D01*
G01X1088871Y191965D02*
X1073210Y181000D01*
G01X1044138Y236761D02*
X1061989Y262254D01*
G01X1045072Y235827D02*
X1063220Y261744D01*
G01X1047372Y234213D02*
X1067001Y262246D01*
G01X1048306Y233279D02*
X1068232Y261736D01*
G01X1042950Y229529D02*
X1048306Y233279D01*
G01X1071480Y258848D02*
X1050150Y228386D01*
G01X1072711Y258338D02*
X1051084Y227452D01*
G01X1055884Y226767D02*
X1077636Y257832D01*
G01X1056818Y225833D02*
X1078867Y257322D01*
G01X1059540Y224757D02*
X1085366Y261641D01*
G01X1060474Y223823D02*
X1086597Y261131D01*
G01X1042777Y211431D02*
X1060474Y223823D01*
G01X1045072Y235827D02*
X1063220Y261744D01*
G01X1044138Y236761D02*
X1061989Y262254D01*
G01X1048306Y233279D02*
X1068232Y261736D01*
G01X1047372Y234213D02*
X1067001Y262246D01*
G01X1042950Y229529D02*
X1048306Y233279D01*
G01X1072711Y258338D02*
X1051084Y227452D01*
G01X1071480Y258848D02*
X1050150Y228386D01*
G01X1056818Y225833D02*
X1078867Y257322D01*
G01X1055884Y226767D02*
X1077636Y257832D01*
G01X1060474Y223823D02*
X1086597Y261131D01*
G01X1059540Y224757D02*
X1085366Y261641D01*
G01X1042777Y211431D02*
X1060474Y223823D01*
G01X1064584Y222023D02*
X1092152Y261393D01*
G01X1065518Y221089D02*
X1093383Y260883D01*
G01X1055828Y214305D02*
X1065518Y221089D01*
G01X1099677Y262874D02*
X1068259Y218005D01*
G01X1100908Y262364D02*
X1069194Y217073D01*
G01X1106466Y263796D02*
X1071909Y214443D01*
G01X1072843Y213509D02*
X1090252Y238373D01*
G01X1110643Y262960D02*
X1074019Y210656D01*
G01X1111874Y262450D02*
X1074953Y209722D01*
G01X1065518Y221089D02*
X1093383Y260883D01*
G01X1064584Y222023D02*
X1092152Y261393D01*
G01X1055828Y214305D02*
X1065518Y221089D01*
G01X1100908Y262364D02*
X1069194Y217073D01*
G01X1099677Y262874D02*
X1068259Y218005D01*
G01X1106466Y263796D02*
X1071909Y214443D01*
G01X1072843Y213509D02*
X1090252Y238373D01*
G01X1106466Y263796D02*
X1071909Y214443D01*
G01X1111874Y262450D02*
X1074953Y209722D01*
G01X1110643Y262960D02*
X1074019Y210656D01*
G01X1046269Y260510D02*
X1126346Y714648D01*
G01X1047500Y260000D02*
X1127667Y714648D01*
G01X1052509Y258863D02*
X1132522Y712715D01*
G01X1053740Y258353D02*
X1093797Y485564D01*
G01X1061989Y262254D02*
X1142128Y716745D01*
G01X1063220Y261744D02*
X1143449Y716745D01*
G01X1067001Y262246D02*
X1151922Y743859D01*
G01X1068232Y261736D02*
X1153243Y743859D01*
G01X1150919Y709376D02*
X1071480Y258848D01*
G01X1152150Y708866D02*
X1072711Y258338D01*
G01X1047500Y260000D02*
X1127667Y714648D01*
G01X1046269Y260510D02*
X1126346Y714648D01*
G01X1052509Y258863D02*
X1132522Y712715D01*
G01X1053740Y258353D02*
X1093797Y485564D01*
G01X1052509Y258863D02*
X1132522Y712715D01*
G01X1063220Y261744D02*
X1143449Y716745D01*
G01X1061989Y262254D02*
X1142128Y716745D01*
G01X1068232Y261736D02*
X1153243Y743859D01*
G01X1067001Y262246D02*
X1151922Y743859D01*
G01X1152150Y708866D02*
X1072711Y258338D01*
G01X1150919Y709376D02*
X1071480Y258848D01*
G01X1045750Y316434D02*
X1113015Y697909D01*
G01X1046981Y315924D02*
X1114336Y697909D01*
G01X1046981Y315924D02*
X1114336Y697909D01*
G01X1045750Y316434D02*
X1113015Y697909D01*
G01X1074321Y507143D02*
X1108304Y699871D01*
G01X1074321Y507143D02*
X1108304Y699871D01*
G01X1062861Y640315D02*
X1043430Y750447D01*
G01X1064182Y640315D02*
X1044751Y750447D01*
G01X1064182Y640315D02*
X1044751Y750447D01*
G01X1062861Y640315D02*
X1043430Y750447D01*
G01X1076955Y694208D02*
X1060930Y785087D01*
G01X1078276Y694208D02*
X1062251Y785087D01*
G01X1078276Y694208D02*
X1062251Y785087D01*
G01X1076955Y694208D02*
X1060930Y785087D01*
G01X1042655Y778025D02*
X1047500Y805500D01*
G01X1043430Y750447D02*
X1054686Y814291D01*
G01X1044751Y750447D02*
X1056007Y814291D01*
G01X1042655Y778025D02*
X1047500Y805500D01*
G01X1044751Y750447D02*
X1056007Y814291D01*
G01X1043430Y750447D02*
X1054686Y814291D01*
G01X1044408Y815543D02*
X1043450Y816913D01*
G01X1045639Y816053D02*
X1044515Y817659D01*
G01X1045293Y810523D02*
X1044408Y815543D01*
G01X1047500Y805500D02*
X1045639Y816053D01*
G01X1046179Y805500D02*
X1045293Y810523D01*
G01X1047500Y805500D02*
X1045639Y816053D01*
G01X1056007Y814291D02*
X1055000Y820000D01*
G01X1056007Y814291D02*
X1055000Y820000D01*
G01X1054686Y814291D02*
X1054222Y816920D01*
G01X1056007Y814291D02*
X1055000Y820000D01*
G01X1060930Y785087D02*
X1067569Y822746D01*
G01X1062251Y785087D02*
X1068869Y822632D01*
G01X1045639Y816053D02*
X1044515Y817659D01*
G01X1044408Y815543D02*
X1043450Y816913D01*
G01X1047500Y805500D02*
X1045639Y816053D01*
G01X1045293Y810523D02*
X1044408Y815543D01*
G01X1046179Y805500D02*
X1045293Y810523D01*
G01X1056007Y814291D02*
X1055000Y820000D01*
G01X1054686Y814291D02*
X1054222Y816920D01*
G01X1062251Y785087D02*
X1068869Y822632D01*
G01X1060930Y785087D02*
X1067569Y822746D01*
G01X1042400Y818413D02*
Y828337D01*
G01X1043700Y818823D02*
Y828336D01*
G01X1043450Y816913D02*
X1042400Y818413D01*
G01X1044515Y817659D02*
X1043700Y818823D01*
G01X1054862Y826710D02*
Y828800D01*
G01X1056162Y826594D02*
Y828800D01*
G01X1053679Y820000D02*
X1054862Y826710D01*
G01X1055000Y820000D02*
X1056162Y826594D01*
G01X1054043Y817935D02*
X1053679Y820000D01*
G01X1054222Y816920D02*
X1054043Y817935D01*
G01X1067569Y822746D02*
Y828400D01*
G01X1068869Y822632D02*
Y828275D01*
G01X1043700Y818823D02*
Y828336D01*
G01X1042400Y818413D02*
Y828337D01*
G01X1044515Y817659D02*
X1043700Y818823D01*
G01X1043450Y816913D02*
X1042400Y818413D01*
G01X1056162Y826594D02*
Y828800D01*
G01X1054862Y826710D02*
Y828800D01*
G01X1055000Y820000D02*
X1056162Y826594D01*
G01X1053679Y820000D02*
X1054862Y826710D01*
G01X1054043Y817935D02*
X1053679Y820000D01*
G01X1054222Y816920D02*
X1054043Y817935D01*
G01X1068869Y822632D02*
Y828275D01*
G01X1067569Y822746D02*
Y828400D01*
G01X1091621Y108929D02*
X1085110Y104369D01*
G01X1090687Y109863D02*
X1084600Y105600D01*
G01X1090687Y109863D02*
X1084600Y105600D01*
G01X1091621Y108929D02*
X1085110Y104369D01*
G01X1094163Y104325D02*
X1087216Y99461D01*
G01X1086706Y100692D02*
X1093229Y105259D01*
G01X1101704Y115094D02*
X1094163Y104325D01*
G01X1093229Y105259D02*
X1100473Y115604D01*
G01X1097420Y99273D02*
X1105041Y111009D01*
G01X1096480Y100213D02*
X1103806Y111496D01*
G01X1078396Y86919D02*
X1097420Y99273D01*
G01X1077890Y88141D02*
X1096480Y100213D01*
G01X1102682Y96573D02*
X1111789Y109580D01*
G01X1101762Y97526D02*
X1110558Y110090D01*
G01X1082957Y83761D02*
X1102682Y96573D01*
G01X1082451Y84983D02*
X1101762Y97526D01*
G01X1093229Y105259D02*
X1100473Y115604D01*
G01X1101704Y115094D02*
X1094163Y104325D01*
G01X1086706Y100692D02*
X1093229Y105259D01*
G01X1094163Y104325D02*
X1087216Y99461D01*
G01X1096480Y100213D02*
X1103806Y111496D01*
G01X1097420Y99273D02*
X1105041Y111009D01*
G01X1077890Y88141D02*
X1096480Y100213D01*
G01X1078396Y86919D02*
X1097420Y99273D01*
G01X1101762Y97526D02*
X1110558Y110090D01*
G01X1102682Y96573D02*
X1111789Y109580D01*
G01X1082451Y84983D02*
X1101762Y97526D01*
G01X1082957Y83761D02*
X1102682Y96573D01*
G01X1091970Y139831D02*
X1097706Y148023D01*
G01X1096772Y148957D02*
X1091036Y140765D01*
G01X1077233Y129513D02*
X1091970Y139831D01*
G01X1091036Y140765D02*
X1076723Y130744D01*
G01X1093479Y133248D02*
X1077381Y121975D01*
G01X1092545Y134182D02*
X1076871Y123206D01*
G01X1102086Y145539D02*
X1093479Y133248D01*
G01X1101152Y146473D02*
X1092545Y134182D01*
G01X1096606Y129955D02*
X1079201Y117768D01*
G01X1095672Y130889D02*
X1078691Y118999D01*
G01X1104155Y140736D02*
X1096606Y129955D01*
G01X1103221Y141670D02*
X1095672Y130889D01*
G01X1118744Y150951D02*
X1104155Y140736D01*
G01X1118234Y152182D02*
X1103221Y141670D01*
G01X1091036Y140765D02*
X1076723Y130744D01*
G01X1077233Y129513D02*
X1091970Y139831D01*
G01X1096772Y148957D02*
X1091036Y140765D01*
G01X1091970Y139831D02*
X1097706Y148023D01*
G01X1092545Y134182D02*
X1076871Y123206D01*
G01X1093479Y133248D02*
X1077381Y121975D01*
G01X1101152Y146473D02*
X1092545Y134182D01*
G01X1102086Y145539D02*
X1093479Y133248D01*
G01X1095672Y130889D02*
X1078691Y118999D01*
G01X1096606Y129955D02*
X1079201Y117768D01*
G01X1103221Y141670D02*
X1095672Y130889D01*
G01X1104155Y140736D02*
X1096606Y129955D01*
G01X1118234Y152182D02*
X1103221Y141670D01*
G01X1118744Y150951D02*
X1104155Y140736D01*
G01X1096938Y116522D02*
X1091621Y108929D01*
G01X1095707Y117032D02*
X1090687Y109863D01*
G01X1098731Y126690D02*
X1096938Y116522D01*
G01X1097500Y127200D02*
X1095707Y117032D01*
G01X1107066Y138594D02*
X1098731Y126690D01*
G01X1106132Y139528D02*
X1097500Y127200D01*
G01X1120056Y147689D02*
X1107066Y138594D01*
G01X1119547Y148920D02*
X1106132Y139528D01*
G01X1095707Y117032D02*
X1090687Y109863D01*
G01X1096938Y116522D02*
X1091621Y108929D01*
G01X1097500Y127200D02*
X1095707Y117032D01*
G01X1098731Y126690D02*
X1096938Y116522D01*
G01X1106132Y139528D02*
X1097500Y127200D01*
G01X1107066Y138594D02*
X1098731Y126690D01*
G01X1119547Y148920D02*
X1106132Y139528D01*
G01X1120056Y147689D02*
X1107066Y138594D01*
G01X1104031Y128290D02*
X1101704Y115094D01*
G01X1100473Y115604D02*
X1102800Y128800D01*
G01X1109431Y136003D02*
X1104031Y128290D01*
G01X1102800Y128800D02*
X1108497Y136937D01*
G01X1121404Y144387D02*
X1109431Y136003D01*
G01X1108497Y136937D02*
X1120894Y145618D01*
G01X1107740Y126287D02*
X1112300Y132800D01*
G01X1106509Y126797D02*
X1111366Y133733D01*
G01X1105041Y111009D02*
X1107740Y126287D01*
G01X1103806Y111496D02*
X1106509Y126797D01*
G01X1108497Y136937D02*
X1120894Y145618D01*
G01X1121404Y144387D02*
X1109431Y136003D01*
G01X1102800Y128800D02*
X1108497Y136937D01*
G01X1109431Y136003D02*
X1104031Y128290D01*
G01X1100473Y115604D02*
X1102800Y128800D01*
G01X1104031Y128290D02*
X1101704Y115094D01*
G01X1106509Y126797D02*
X1111366Y133733D01*
G01X1107740Y126287D02*
X1112300Y132800D01*
G01X1103806Y111496D02*
X1106509Y126797D01*
G01X1105041Y111009D02*
X1107740Y126287D01*
G01X1104451Y186870D02*
X1078468Y168678D01*
G01X1077534Y169612D02*
X1103941Y188101D01*
G01X1106771Y182450D02*
X1080732Y164216D01*
G01X1106261Y183681D02*
X1079798Y165150D01*
G01X1083255Y160119D02*
X1108963Y178120D01*
G01X1082321Y161053D02*
X1108453Y179351D01*
G01X1079190Y154315D02*
X1083255Y160119D01*
G01X1078256Y155249D02*
X1082321Y161053D01*
G01X1077534Y169612D02*
X1103941Y188101D01*
G01X1104451Y186870D02*
X1078468Y168678D01*
G01X1106261Y183681D02*
X1079798Y165150D01*
G01X1106771Y182450D02*
X1080732Y164216D01*
G01X1082321Y161053D02*
X1108453Y179351D01*
G01X1083255Y160119D02*
X1108963Y178120D01*
G01X1078256Y155249D02*
X1082321Y161053D01*
G01X1079190Y154315D02*
X1083255Y160119D01*
G01X1085919Y157423D02*
X1081143Y150602D01*
G01X1086853Y156489D02*
X1082077Y149668D01*
G01X1109566Y173981D02*
X1085919Y157423D01*
G01X1110089Y172759D02*
X1086853Y156489D01*
G01X1143042Y180676D02*
X1109566Y173981D01*
G01X1094288Y150868D02*
X1089189Y143586D01*
G01X1093354Y151802D02*
X1088255Y144520D01*
G01X1111201Y162711D02*
X1094288Y150868D01*
G01X1110678Y163933D02*
X1093354Y151802D01*
G01X1097706Y148023D02*
X1112648Y158485D01*
G01X1112125Y159707D02*
X1096772Y148957D01*
G01X1114945Y154544D02*
X1102086Y145539D01*
G01X1114422Y155766D02*
X1101152Y146473D01*
G01X1086853Y156489D02*
X1082077Y149668D01*
G01X1085919Y157423D02*
X1081143Y150602D01*
G01X1110089Y172759D02*
X1086853Y156489D01*
G01X1109566Y173981D02*
X1085919Y157423D01*
G01X1143042Y180676D02*
X1109566Y173981D01*
G01X1143042Y180676D02*
X1109566Y173981D01*
G01X1085713Y147238D02*
X1084868Y146033D01*
G01X1085360Y149001D02*
X1083935Y146967D01*
G01X1086425Y148255D02*
X1085713Y147238D01*
G01X1085360Y149001D02*
X1083935Y146967D01*
G01X1090831Y154548D02*
X1086425Y148255D01*
G01X1086785Y151036D02*
X1085360Y149001D01*
G01X1089766Y155294D02*
X1086785Y151036D01*
G01X1089897Y155482D02*
X1089765Y155294D01*
G01X1108836Y167154D02*
X1090831Y154548D01*
G01X1108313Y168376D02*
X1089897Y155482D01*
G01X1144569Y174300D02*
X1108836Y167154D01*
G01X1144569Y175626D02*
X1108313Y168376D01*
G01X1093354Y151802D02*
X1088255Y144520D01*
G01X1094288Y150868D02*
X1089189Y143586D01*
G01X1110678Y163933D02*
X1093354Y151802D01*
G01X1111201Y162711D02*
X1094288Y150868D01*
G01X1112125Y159707D02*
X1096772Y148957D01*
G01X1097706Y148023D02*
X1112648Y158485D01*
G01X1114422Y155766D02*
X1101152Y146473D01*
G01X1114945Y154544D02*
X1102086Y145539D01*
G01X1085360Y149001D02*
X1083935Y146967D01*
G01X1085713Y147238D02*
X1084868Y146033D01*
G01X1086425Y148255D02*
X1085713Y147238D01*
G01X1086785Y151036D02*
X1085360Y149001D01*
G01X1090831Y154548D02*
X1086425Y148255D01*
G01X1089766Y155294D02*
X1086785Y151036D01*
G01X1090831Y154548D02*
X1086425Y148255D01*
G01X1089897Y155482D02*
X1089765Y155294D01*
G01X1090831Y154548D02*
X1086425Y148255D01*
G01X1108313Y168376D02*
X1089897Y155482D01*
G01X1108836Y167154D02*
X1090831Y154548D01*
G01X1144569Y175626D02*
X1108313Y168376D01*
G01X1144569Y174300D02*
X1108836Y167154D01*
G01X1079595Y207844D02*
X1111630Y253595D01*
G01X1080660Y207098D02*
X1112776Y252965D01*
G01X1079460Y207709D02*
G03X1079595Y207844I-315J450D01*
G01X1080206Y206644D02*
G03X1080660Y207098I-1061J1515D01*
G01X1083810Y205428D02*
X1113261Y247489D01*
G01X1084744Y204494D02*
X1114407Y246859D01*
G01X1080660Y207098D02*
X1112776Y252965D01*
G01X1079595Y207844D02*
X1111630Y253595D01*
G01X1080206Y206644D02*
G03X1080660Y207098I-1061J1515D01*
G01X1079460Y207709D02*
G03X1079595Y207844I-315J450D01*
G01X1084744Y204494D02*
X1114407Y246859D01*
G01X1083810Y205428D02*
X1113261Y247489D01*
G01X1084772Y199926D02*
X1114355Y242176D01*
G01X1085706Y198992D02*
X1115501Y241546D01*
G01X1086554Y196875D02*
X1116758Y240010D01*
G01X1087488Y195941D02*
X1117904Y239380D01*
G01X1118800Y236976D02*
X1087937Y192899D01*
G01X1119946Y236346D02*
X1088871Y191965D01*
G01X1102902Y191235D02*
X1135590Y196999D01*
G01X1135605Y198322D02*
X1102392Y192466D01*
G01X1137856Y192761D02*
X1104451Y186870D01*
G01X1103941Y188101D02*
X1137871Y194084D01*
G01X1139676Y188252D02*
X1106771Y182450D01*
G01X1139691Y189575D02*
X1106261Y183681D01*
G01X1108963Y178120D02*
X1141830Y183917D01*
G01X1108453Y179351D02*
X1141845Y185240D01*
G01X1085706Y198992D02*
X1115501Y241546D01*
G01X1084772Y199926D02*
X1114355Y242176D01*
G01X1087488Y195941D02*
X1117904Y239380D01*
G01X1086554Y196875D02*
X1116758Y240010D01*
G01X1119946Y236346D02*
X1088871Y191965D01*
G01X1118800Y236976D02*
X1087937Y192899D01*
G01X1135605Y198322D02*
X1102392Y192466D01*
G01X1102902Y191235D02*
X1135590Y196999D01*
G01X1103941Y188101D02*
X1137871Y194084D01*
G01X1137856Y192761D02*
X1104451Y186870D01*
G01X1139691Y189575D02*
X1106261Y183681D01*
G01X1139676Y188252D02*
X1106771Y182450D01*
G01X1108453Y179351D02*
X1141845Y185240D01*
G01X1108963Y178120D02*
X1141830Y183917D01*
G01X1090252Y238373D02*
X1107697Y263286D01*
G01X1090252Y238373D02*
X1107697Y263286D01*
G01X1077636Y257832D02*
X1153164Y686717D01*
G01X1078867Y257322D02*
X1154415Y686321D01*
G01X1085366Y261641D02*
X1157459Y670494D01*
G01X1086597Y261131D02*
X1158690Y669984D01*
G01X1078867Y257322D02*
X1154415Y686321D01*
G01X1077636Y257832D02*
X1153164Y686717D01*
G01X1086597Y261131D02*
X1158690Y669984D01*
G01X1085366Y261641D02*
X1157459Y670494D01*
G01X1092152Y261393D02*
X1162742Y661730D01*
G01X1093383Y260883D02*
X1163973Y661220D01*
G01X1169024Y656160D02*
X1099677Y262874D01*
G01X1170255Y655650D02*
X1100908Y262364D01*
G01X1170110Y624734D02*
X1106466Y263796D01*
G01X1107697Y263286D02*
X1171341Y624224D01*
G01X1093383Y260883D02*
X1163973Y661220D01*
G01X1092152Y261393D02*
X1162742Y661730D01*
G01X1170255Y655650D02*
X1100908Y262364D01*
G01X1169024Y656160D02*
X1099677Y262874D01*
G01X1107697Y263286D02*
X1171341Y624224D01*
G01X1170110Y624734D02*
X1106466Y263796D01*
G01X1093797Y485564D02*
X1133843Y712715D01*
G01X1093797Y485564D02*
X1133843Y712715D01*
G01X1106983Y699871D02*
X1090666Y792411D01*
G01X1108304Y699871D02*
X1091987Y792411D01*
G01X1108304Y699871D02*
X1091987Y792411D01*
G01X1106983Y699871D02*
X1090666Y792411D01*
G01X1100490Y703086D02*
X1080736Y803618D01*
G01X1101762Y703358D02*
X1082015Y803856D01*
G01X1101553Y698500D02*
X1100490Y703086D01*
G01X1102887Y698505D02*
X1101762Y703358D01*
G01D02*
X1082015Y803856D01*
G01X1100490Y703086D02*
X1080736Y803618D01*
G01X1102887Y698505D02*
X1101762Y703358D01*
G01X1101553Y698500D02*
X1100490Y703086D01*
G01X1113015Y697909D02*
X1098789Y778591D01*
G01X1114336Y697909D02*
X1100110Y778591D01*
G01X1114336Y697909D02*
X1100110Y778591D01*
G01X1113015Y697909D02*
X1098789Y778591D01*
G01X1100110D02*
X1107617Y821161D01*
G01X1098789Y778591D02*
X1102583Y800102D01*
G01X1100110Y778591D02*
X1107617Y821161D01*
G01X1100110Y778591D02*
X1107617Y821161D01*
G01X1098789Y778591D02*
X1102583Y800102D01*
G01X1094539Y814376D02*
X1092657Y825048D01*
G01X1095860Y814376D02*
X1093957Y825162D01*
G01X1090666Y792411D02*
X1094539Y814376D01*
G01X1091987Y792411D02*
X1095860Y814376D01*
G01X1102583Y800102D02*
X1106296Y821161D01*
G01X1095860Y814376D02*
X1093957Y825162D01*
G01X1094539Y814376D02*
X1092657Y825048D01*
G01X1091987Y792411D02*
X1095860Y814376D01*
G01X1090666Y792411D02*
X1094539Y814376D01*
G01X1102583Y800102D02*
X1106296Y821161D01*
G01X1080059Y807458D02*
Y828007D01*
G01X1081359Y807572D02*
Y828007D01*
G01X1080736Y803618D02*
X1080059Y807458D01*
G01X1082015Y803856D02*
X1081359Y807572D01*
G01D02*
Y828007D01*
G01X1080059Y807458D02*
Y828007D01*
G01X1082015Y803856D02*
X1081359Y807572D01*
G01X1080736Y803618D02*
X1080059Y807458D01*
G01X1092657Y825048D02*
Y828007D01*
G01X1093957Y825162D02*
Y828007D01*
G01X1105256Y827061D02*
Y828007D01*
G01X1106556Y827175D02*
Y828007D01*
G01X1106296Y821161D02*
X1105256Y827061D01*
G01X1107617Y821161D02*
X1106556Y827175D01*
G01X1093957Y825162D02*
Y828007D01*
G01X1092657Y825048D02*
Y828007D01*
G01X1106556Y827175D02*
Y828007D01*
G01X1105256Y827061D02*
Y828007D01*
G01X1107617Y821161D02*
X1106556Y827175D01*
G01X1106296Y821161D02*
X1105256Y827061D01*
G01X1139205Y140706D02*
G02X1139600Y139752I-954J-954D01*
G01X1140125Y141626D02*
G02X1140900Y139751I-1875J-1872D01*
G01X1137288Y141500D02*
G02X1139205Y140706I0J-2711D01*
G01X1137288Y142800D02*
G02X1140125Y141626I1J-4012D01*
G01X1136197Y141500D02*
X1137288D01*
G01X1120370Y140041D02*
X1136083Y142800D01*
G01X1120880Y138810D02*
X1136197Y141500D01*
G01X1120370Y140041D02*
X1136083Y142800D01*
G01X1112300Y132800D02*
X1120880Y138810D01*
G01X1111366Y133733D02*
X1120370Y140041D01*
G01X1118495Y131100D02*
X1120490D01*
G01X1118084Y132400D02*
X1120074D01*
G01X1115561Y129044D02*
X1118495Y131100D01*
G01X1114627Y129978D02*
X1118084Y132400D01*
G01X1115107Y128396D02*
X1115561Y129044D01*
G01X1113876Y128906D02*
X1114627Y129978D01*
G01X1111789Y109580D02*
X1115107Y128396D01*
G01X1112879Y123255D02*
X1113876Y128906D01*
G01X1110558Y110090D02*
X1112350Y120251D01*
G01X1140125Y141626D02*
G02X1140900Y139751I-1875J-1872D01*
G01X1139205Y140706D02*
G02X1139600Y139752I-954J-954D01*
G01X1137288Y142800D02*
G02X1140125Y141626I1J-4012D01*
G01X1137288Y141500D02*
G02X1139205Y140706I0J-2711D01*
G01X1136197Y141500D02*
X1137288D01*
G01X1120370Y140041D02*
X1136083Y142800D01*
G01X1136197Y141500D02*
X1137288D01*
G01X1120880Y138810D02*
X1136197Y141500D01*
G01X1111366Y133733D02*
X1120370Y140041D01*
G01X1112300Y132800D02*
X1120880Y138810D01*
G01X1118084Y132400D02*
X1120074D01*
G01X1118495Y131100D02*
X1120490D01*
G01X1114627Y129978D02*
X1118084Y132400D01*
G01X1115561Y129044D02*
X1118495Y131100D01*
G01X1113876Y128906D02*
X1114627Y129978D01*
G01X1115107Y128396D02*
X1115561Y129044D01*
G01X1112879Y123255D02*
X1113876Y128906D01*
G01X1111789Y109580D02*
X1115107Y128396D01*
G01X1110558Y110090D02*
X1112350Y120251D01*
G01X1111789Y109580D02*
X1115107Y128396D01*
G01X1126563Y176053D02*
X1110089Y172759D01*
G01X1146646Y169800D02*
X1111201Y162711D01*
G01X1146646Y171126D02*
X1110678Y163933D01*
G01X1112648Y158485D02*
X1146779Y165312D01*
G01X1146764Y166635D02*
X1112125Y159707D01*
G01X1146562Y160732D02*
X1114945Y154544D01*
G01X1146550Y162055D02*
X1114425Y155767D01*
G01X1167465Y159537D02*
X1118744Y150951D01*
G01X1167465Y160858D02*
X1118234Y152182D01*
G01X1126563Y176053D02*
X1110089Y172759D01*
G01X1146646Y171126D02*
X1110678Y163933D01*
G01X1146646Y169800D02*
X1111201Y162711D01*
G01X1146764Y166635D02*
X1112125Y159707D01*
G01X1112648Y158485D02*
X1146779Y165312D01*
G01X1146550Y162055D02*
X1114425Y155767D01*
G01X1146562Y160732D02*
X1114945Y154544D01*
G01X1167465Y160858D02*
X1118234Y152182D01*
G01X1167465Y159537D02*
X1118744Y150951D01*
G01X1133147Y149996D02*
X1120056Y147689D01*
G01X1133147Y151317D02*
X1119547Y148920D01*
G01X1148579Y147275D02*
X1133147Y149996D01*
G01X1160547Y146485D02*
X1133147Y151317D01*
G01X1160547Y146485D02*
X1133147Y151317D01*
G01D02*
X1119547Y148920D01*
G01X1133147Y149996D02*
X1120056Y147689D01*
G01X1160547Y146485D02*
X1133147Y151317D01*
G01X1148579Y147275D02*
X1133147Y149996D01*
G01X1133364Y146495D02*
X1121404Y144387D01*
G01X1120894Y145618D02*
X1133364Y147816D01*
G01X1157484Y142240D02*
X1133364Y146495D01*
G01Y147816D02*
X1157780Y143509D01*
G01X1136083Y142800D02*
X1137288D01*
G01X1133364Y147816D02*
X1157780Y143509D01*
G01X1157484Y142240D02*
X1133364Y146495D01*
G01X1120894Y145618D02*
X1133364Y147816D01*
G01Y146495D02*
X1121404Y144387D01*
G01X1136083Y142800D02*
X1137288D01*
G01X1135590Y196999D02*
X1147084Y194700D01*
G01Y196026D02*
X1135605Y198322D01*
G01X1149411Y190450D02*
X1137856Y192761D01*
G01X1137871Y194084D02*
X1149411Y191776D01*
G01X1149038Y186380D02*
X1139676Y188252D01*
G01X1149038Y187706D02*
X1139691Y189575D01*
G01X1141830Y183917D02*
X1149367Y182410D01*
G01X1141845Y185240D02*
X1149367Y183736D01*
G01X1147084Y196026D02*
X1135605Y198322D01*
G01X1135590Y196999D02*
X1147084Y194700D01*
G01X1137871Y194084D02*
X1149411Y191776D01*
G01Y190450D02*
X1137856Y192761D01*
G01X1149038Y187706D02*
X1139691Y189575D01*
G01X1149038Y186380D02*
X1139676Y188252D01*
G01X1141845Y185240D02*
X1149367Y183736D01*
G01X1141830Y183917D02*
X1149367Y182410D01*
G01X1143042Y179350D02*
X1126563Y176054D01*
G01X1149229Y179439D02*
X1143042Y180676D01*
G01X1149229Y178113D02*
X1143042Y179350D01*
G01D02*
X1126563Y176054D01*
G01X1149229Y178113D02*
X1143042Y179350D01*
G01X1149229Y179439D02*
X1143042Y180676D01*
G01X1114355Y242176D02*
X1147232Y321208D01*
G01X1115501Y241546D02*
X1148488Y320842D01*
G01X1116758Y240010D02*
X1151337Y323133D01*
G01X1117904Y239380D02*
X1152593Y322766D01*
G01X1155769Y325844D02*
X1118800Y236976D01*
G01X1157025Y325477D02*
X1119946Y236346D01*
G01X1115501Y241546D02*
X1148488Y320842D01*
G01X1114355Y242176D02*
X1147232Y321208D01*
G01X1117904Y239380D02*
X1152593Y322766D01*
G01X1116758Y240010D02*
X1151337Y323133D01*
G01X1157025Y325477D02*
X1119946Y236346D01*
G01X1155769Y325844D02*
X1118800Y236976D01*
G01X1172346Y612874D02*
X1110643Y262960D01*
G01X1173577Y612364D02*
X1111874Y262450D01*
G01X1111630Y253595D02*
X1128088Y293159D01*
G01X1112776Y252965D02*
X1129344Y292792D01*
G01X1113261Y247489D02*
X1141101Y314413D01*
G01X1114407Y246859D02*
X1142357Y314047D01*
G01X1173577Y612364D02*
X1111874Y262450D01*
G01X1172346Y612874D02*
X1110643Y262960D01*
G01X1112776Y252965D02*
X1129344Y292792D01*
G01X1111630Y253595D02*
X1128088Y293159D01*
G01X1114407Y246859D02*
X1142357Y314047D01*
G01X1113261Y247489D02*
X1141101Y314413D01*
G01X1128088Y293159D02*
X1185162Y616585D01*
G01X1129344Y292792D02*
X1186393Y616075D01*
G01X1129344Y292792D02*
X1186393Y616075D01*
G01X1128088Y293159D02*
X1185162Y616585D01*
G01X1141101Y314413D02*
X1195292Y623376D01*
G01X1142357Y314047D02*
X1169440Y468456D01*
G01X1141101Y314413D02*
X1195292Y623376D01*
G01X1142357Y314047D02*
X1169440Y468456D01*
G01X1141101Y314413D02*
X1195292Y623376D01*
G01X1126346Y714648D02*
X1114943Y779315D01*
G01X1127667Y714648D02*
X1116264Y779315D01*
G01X1133843Y712715D02*
X1127637Y747916D01*
G01X1132522Y712715D02*
X1129459Y730090D01*
G01X1133843Y712715D02*
X1127637Y747916D01*
G01X1127667Y714648D02*
X1116264Y779315D01*
G01X1126346Y714648D02*
X1114943Y779315D01*
G01X1133843Y712715D02*
X1127637Y747916D01*
G01X1132522Y712715D02*
X1129459Y730090D01*
G01X1126316Y747916D02*
X1134788Y795969D01*
G01X1127637Y747916D02*
X1136109Y795969D01*
G01X1129459Y730090D02*
X1126316Y747916D01*
G01X1142128Y716745D02*
X1136092Y750974D01*
G01X1143449Y716745D02*
X1137413Y750974D01*
G01X1127637Y747916D02*
X1136109Y795969D01*
G01X1126316Y747916D02*
X1134788Y795969D01*
G01X1129459Y730090D02*
X1126316Y747916D01*
G01X1143449Y716745D02*
X1137413Y750974D01*
G01X1142128Y716745D02*
X1136092Y750974D01*
G01X1114943Y779315D02*
X1118679Y800500D01*
G01X1116264Y779315D02*
X1120000Y800500D01*
G01X1136092Y750974D02*
X1145707Y805500D01*
G01X1137413Y750974D02*
X1147028Y805500D01*
G01X1116264Y779315D02*
X1120000Y800500D01*
G01X1114943Y779315D02*
X1118679Y800500D01*
G01X1137413Y750974D02*
X1147028Y805500D01*
G01X1136092Y750974D02*
X1145707Y805500D01*
G01X1116018Y815589D02*
X1117854Y826000D01*
G01X1117339Y815589D02*
X1119154Y825883D01*
G01X1118679Y800500D02*
X1116018Y815589D01*
G01X1120000Y800500D02*
X1117339Y815589D01*
G01X1134788Y795969D02*
X1130453Y820556D01*
G01X1136109Y795969D02*
X1131753Y820670D01*
G01X1117339Y815589D02*
X1119154Y825883D01*
G01X1116018Y815589D02*
X1117854Y826000D01*
G01X1120000Y800500D02*
X1117339Y815589D01*
G01X1118679Y800500D02*
X1116018Y815589D01*
G01X1136109Y795969D02*
X1131753Y820670D01*
G01X1134788Y795969D02*
X1130453Y820556D01*
G01X1117854Y826000D02*
Y828007D01*
G01X1119154Y825883D02*
Y828600D01*
G01X1130453Y820556D02*
Y828007D01*
G01X1131753Y820670D02*
Y828007D01*
G01X1143051Y820561D02*
Y828007D01*
G01X1145707Y805500D02*
X1143051Y820561D01*
G01X1119154Y825883D02*
Y828600D01*
G01X1117854Y826000D02*
Y828007D01*
G01X1131753Y820670D02*
Y828007D01*
G01X1130453Y820556D02*
Y828007D01*
G01X1143051Y820561D02*
Y828007D01*
G01X1145707Y805500D02*
X1143051Y820561D01*
G01X1159006Y140254D02*
G03X1157484Y142240I-2057J0D01*
G01X1157782Y143507D02*
G02X1160307Y140254I-833J-3253D01*
G01X1158407Y138804D02*
G03X1159007Y140254I-1450J1449D01*
G01X1157782Y143507D02*
G02X1160307Y140254I-833J-3253D01*
G01X1157782Y143507D02*
G02X1160307Y140254I-833J-3253D01*
G01X1159006D02*
G03X1157484Y142240I-2057J0D01*
G01X1158407Y138804D02*
G03X1159007Y140254I-1450J1449D01*
G01X1149225Y169284D02*
X1146646Y169800D01*
G01X1149225Y170610D02*
X1146646Y171126D01*
G01X1165404Y172520D02*
X1149225Y169284D01*
G01X1165404Y173846D02*
X1149225Y170610D01*
G01X1207897Y164021D02*
X1165404Y172520D01*
G01X1208379Y165251D02*
X1165404Y173846D01*
G01X1200364Y163586D02*
X1167662Y169647D01*
G01X1167690Y168319D02*
X1183822Y165329D01*
G01X1200364Y163586D02*
X1167662Y169647D01*
G01X1151176Y164536D02*
X1167690Y168319D01*
G01X1167662Y169647D02*
X1151142Y165863D01*
G01X1146779Y165312D02*
X1151176Y164536D01*
G01X1151142Y165863D02*
X1146764Y166635D01*
G01X1150119Y160105D02*
X1146562Y160732D01*
G01X1150119Y161426D02*
X1146550Y162055D01*
G01X1169590Y163538D02*
X1150119Y160105D01*
G01X1169595Y164859D02*
X1150119Y161426D01*
G01X1187064Y160322D02*
X1169590Y163538D01*
G01X1187578Y161550D02*
X1169595Y164859D01*
G01X1183814Y156653D02*
X1167465Y159537D01*
G01X1184324Y157884D02*
X1167465Y160858D01*
G01X1148104Y173593D02*
X1144569Y174300D01*
G01X1148104Y174919D02*
X1144569Y175626D01*
G01X1163859Y176744D02*
X1148104Y173593D01*
G01X1163859Y178070D02*
X1148104Y174919D01*
G01X1185644Y172387D02*
X1163859Y176744D01*
G01X1149225Y170610D02*
X1146646Y171126D01*
G01X1149225Y169284D02*
X1146646Y169800D01*
G01X1165404Y173846D02*
X1149225Y170610D01*
G01X1165404Y172520D02*
X1149225Y169284D01*
G01X1208379Y165251D02*
X1165404Y173846D01*
G01X1207897Y164021D02*
X1165404Y172520D01*
G01X1151142Y165863D02*
X1146764Y166635D01*
G01X1146779Y165312D02*
X1151176Y164536D01*
G01X1167662Y169647D02*
X1151142Y165863D01*
G01X1151176Y164536D02*
X1167690Y168319D01*
G01X1200364Y163586D02*
X1167662Y169647D01*
G01X1167690Y168319D02*
X1183822Y165329D01*
G01X1150119Y161426D02*
X1146550Y162055D01*
G01X1150119Y160105D02*
X1146562Y160732D01*
G01X1169595Y164859D02*
X1150119Y161426D01*
G01X1169590Y163538D02*
X1150119Y160105D01*
G01X1187578Y161550D02*
X1169595Y164859D01*
G01X1187064Y160322D02*
X1169590Y163538D01*
G01X1184324Y157884D02*
X1167465Y160858D01*
G01X1183814Y156653D02*
X1167465Y159537D01*
G01X1148104Y174919D02*
X1144569Y175626D01*
G01X1148104Y173593D02*
X1144569Y174300D01*
G01X1163859Y178070D02*
X1148104Y174919D01*
G01X1163859Y176744D02*
X1148104Y173593D01*
G01X1185644Y172387D02*
X1163859Y176744D01*
G01X1164548Y144459D02*
X1148579Y147275D01*
G01X1164461Y145795D02*
X1160547Y146485D01*
G01X1173977Y147422D02*
X1164548Y144459D01*
G01X1168873Y147181D02*
X1164461Y145795D01*
G01X1171231Y147922D02*
X1168873Y147181D01*
G01X1173971Y148783D02*
X1171231Y147922D01*
G01X1178878Y145929D02*
X1173977Y147422D01*
G01X1179568Y147078D02*
X1173971Y148783D01*
G01X1164548Y144459D02*
X1148579Y147275D01*
G01X1164461Y145795D02*
X1160547Y146485D01*
G01X1164548Y144459D02*
X1148579Y147275D01*
G01X1168873Y147181D02*
X1164461Y145795D01*
G01X1173977Y147422D02*
X1164548Y144459D01*
G01X1171231Y147922D02*
X1168873Y147181D01*
G01X1173977Y147422D02*
X1164548Y144459D01*
G01X1173971Y148783D02*
X1171231Y147922D01*
G01X1173977Y147422D02*
X1164548Y144459D01*
G01X1179568Y147078D02*
X1173971Y148783D01*
G01X1178878Y145929D02*
X1173977Y147422D01*
G01X1172084Y194700D02*
X1184584Y197200D01*
G01Y198526D02*
X1172084Y196026D01*
G01X1159584Y197200D02*
X1172084Y194700D01*
G01Y196026D02*
X1159584Y198526D01*
G01X1147084Y194700D02*
X1159584Y197200D01*
G01Y198526D02*
X1147084Y196026D01*
G01X1161911Y192950D02*
X1149411Y190450D01*
G01Y191776D02*
X1161911Y194276D01*
G01X1174411Y190450D02*
X1161911Y192950D01*
G01Y194276D02*
X1174411Y191776D01*
G01X1186911Y192950D02*
X1174411Y190450D01*
G01Y191776D02*
X1186911Y194276D01*
G01X1161538Y188880D02*
X1149038Y186380D01*
G01X1161538Y190206D02*
X1149038Y187706D01*
G01X1176438Y185900D02*
X1161538Y188880D01*
G01X1176438Y187226D02*
X1161538Y190206D01*
G01X1188938Y188400D02*
X1176438Y185900D01*
G01X1188938Y189726D02*
X1176438Y187226D01*
G01X1161867Y184910D02*
X1178665Y181550D01*
G01X1161867Y186236D02*
X1178665Y182876D01*
G01X1149367Y182410D02*
X1161867Y184910D01*
G01X1149367Y183736D02*
X1161867Y186236D01*
G01X1159584Y198526D02*
X1147084Y196026D01*
G01Y194700D02*
X1159584Y197200D01*
G01X1172084Y196026D02*
X1159584Y198526D01*
G01Y197200D02*
X1172084Y194700D01*
G01X1184584Y198526D02*
X1172084Y196026D01*
G01Y194700D02*
X1184584Y197200D01*
G01X1174411Y191776D02*
X1186911Y194276D01*
G01Y192950D02*
X1174411Y190450D01*
G01X1161911Y194276D02*
X1174411Y191776D01*
G01Y190450D02*
X1161911Y192950D01*
G01X1149411Y191776D02*
X1161911Y194276D01*
G01Y192950D02*
X1149411Y190450D01*
G01X1161538Y190206D02*
X1149038Y187706D01*
G01X1161538Y188880D02*
X1149038Y186380D01*
G01X1176438Y187226D02*
X1161538Y190206D01*
G01X1176438Y185900D02*
X1161538Y188880D01*
G01X1188938Y189726D02*
X1176438Y187226D01*
G01X1188938Y188400D02*
X1176438Y185900D01*
G01X1161867Y186236D02*
X1178665Y182876D01*
G01X1161867Y184910D02*
X1178665Y181550D01*
G01X1149367Y183736D02*
X1161867Y186236D01*
G01X1149367Y182410D02*
X1161867Y184910D01*
G01X1162662Y182125D02*
X1149229Y179439D01*
G01X1162662Y180799D02*
X1149229Y178113D01*
G01X1181475Y178362D02*
X1162662Y182125D01*
G01X1181475Y177036D02*
X1162662Y180799D01*
G01D02*
X1149229Y178113D01*
G01X1162662Y182125D02*
X1149229Y179439D01*
G01X1181475Y177036D02*
X1162662Y180799D01*
G01X1181475Y178362D02*
X1162662Y182125D01*
G01X1185659Y173710D02*
X1163859Y178070D01*
G01X1185659Y173710D02*
X1163859Y178070D01*
G01X1147232Y321208D02*
X1199785Y620757D01*
G01X1148488Y320842D02*
X1201016Y620248D01*
G01X1151337Y323133D02*
X1203719Y620209D01*
G01X1152593Y322766D02*
X1204950Y619699D01*
G01X1207490Y619081D02*
X1155769Y325844D01*
G01X1208721Y618571D02*
X1157025Y325477D01*
G01X1148488Y320842D02*
X1201016Y620248D01*
G01X1147232Y321208D02*
X1199785Y620757D01*
G01X1152593Y322766D02*
X1204950Y619699D01*
G01X1151337Y323133D02*
X1203719Y620209D01*
G01X1208721Y618571D02*
X1157025Y325477D01*
G01X1207490Y619081D02*
X1155769Y325844D01*
G01X1169440Y468456D02*
X1196523Y622866D01*
G01X1169440Y468456D02*
X1196523Y622866D01*
G01X1266269Y747010D02*
X1172346Y612874D01*
G01X1267500Y746500D02*
X1173577Y612364D01*
G01X1267500Y746500D02*
X1173577Y612364D01*
G01X1266269Y747010D02*
X1172346Y612874D01*
G01X1262103Y756115D02*
X1170110Y624734D01*
G01X1171341Y624224D02*
X1263334Y755605D01*
G01X1171341Y624224D02*
X1263334Y755605D01*
G01X1262103Y756115D02*
X1170110Y624734D01*
G01X1157459Y670494D02*
X1215289Y753096D01*
G01X1158690Y669984D02*
X1216520Y752586D01*
G01X1158690Y669984D02*
X1216520Y752586D01*
G01X1157459Y670494D02*
X1215289Y753096D01*
G01X1162742Y661730D02*
X1227086Y753617D01*
G01X1163973Y661220D02*
X1228317Y753107D01*
G01X1245353Y765172D02*
X1169024Y656160D01*
G01X1246584Y764662D02*
X1170255Y655650D01*
G01X1163973Y661220D02*
X1228317Y753107D01*
G01X1162742Y661730D02*
X1227086Y753617D01*
G01X1246584Y764662D02*
X1170255Y655650D01*
G01X1245353Y765172D02*
X1169024Y656160D01*
G01X1174838Y743536D02*
X1150919Y709376D01*
G01X1176069Y743026D02*
X1152150Y708866D01*
G01X1163209Y710359D02*
X1186815Y744074D01*
G01X1164357Y709730D02*
X1188046Y743564D01*
G01X1155600Y691917D02*
X1163209Y710359D01*
G01X1156804Y691426D02*
X1164357Y709730D01*
G01X1155586Y691887D02*
X1155595Y691906D01*
G01X1154415Y686321D02*
X1156763Y691334D01*
G01X1153164Y686717D02*
X1155585Y691887D01*
G01X1154415Y686321D02*
X1156763Y691334D01*
G01X1176069Y743026D02*
X1152150Y708866D01*
G01X1174838Y743536D02*
X1150919Y709376D01*
G01X1164357Y709730D02*
X1188046Y743564D01*
G01X1163209Y710359D02*
X1186815Y744074D01*
G01X1156804Y691426D02*
X1164357Y709730D01*
G01X1155600Y691917D02*
X1163209Y710359D01*
G01X1154415Y686321D02*
X1156763Y691334D01*
G01X1155586Y691887D02*
X1155595Y691906D01*
G01X1153164Y686717D02*
X1155585Y691887D01*
G01X1151922Y743859D02*
X1148220Y764858D01*
G01X1153243Y743859D02*
X1149541Y764858D01*
G01X1181179Y779500D02*
X1174838Y743536D01*
G01X1182500Y779500D02*
X1176069Y743026D01*
G01X1153243Y743859D02*
X1149541Y764858D01*
G01X1151922Y743859D02*
X1148220Y764858D01*
G01X1182500Y779500D02*
X1176069Y743026D01*
G01X1181179Y779500D02*
X1174838Y743536D01*
G01X1148220Y764858D02*
X1157281Y816250D01*
G01X1149541Y764858D02*
X1158602Y816250D01*
G01X1149541Y764858D02*
X1158602Y816250D01*
G01X1148220Y764858D02*
X1157281Y816250D01*
G01X1147028Y805500D02*
X1144351Y820680D01*
G01X1157281Y816250D02*
X1155649Y825509D01*
G01X1158602Y816250D02*
X1157746Y821106D01*
G01X1176755Y804591D02*
X1181179Y779500D01*
G01X1178679Y815500D02*
X1176755Y804591D01*
G01X1147028Y805500D02*
X1144351Y820680D01*
G01X1157281Y816250D02*
X1155649Y825509D01*
G01X1158602Y816250D02*
X1157746Y821106D01*
G01X1157281Y816250D02*
X1155649Y825509D01*
G01X1176755Y804591D02*
X1181179Y779500D01*
G01X1178679Y815500D02*
X1176755Y804591D01*
G01X1144351Y820680D02*
Y828007D01*
G01X1155649Y825509D02*
Y828007D01*
G01X1156949Y825625D02*
Y828007D01*
G01X1157746Y821106D02*
X1156950Y825625D01*
G01X1144351Y820680D02*
Y828007D01*
G01X1156949Y825625D02*
Y828007D01*
G01X1155649Y825509D02*
Y828007D01*
G01X1157746Y821106D02*
X1156950Y825625D01*
G01X1188500Y139987D02*
Y142184D01*
G01X1189800Y140013D02*
Y142071D01*
G01Y140013D02*
Y142071D01*
G01X1188500Y139987D02*
Y142184D01*
G01X1215150Y171514D02*
X1205672Y178150D01*
G01X1214216Y170580D02*
X1205149Y176928D01*
G01X1209195Y163227D02*
X1207897Y164021D01*
G01X1209225Y164733D02*
X1208379Y165251D01*
G01X1210081Y164209D02*
X1209225Y164733D01*
G01X1211380Y160367D02*
X1209195Y163227D01*
G01X1212555Y160972D02*
X1210081Y164209D01*
G01X1204741Y159038D02*
Y157680D01*
G01X1206041D02*
Y159577D01*
G01X1202897Y160882D02*
X1204741Y159038D01*
G01X1206041Y159577D02*
X1203666Y161953D01*
G01X1199949Y162340D02*
X1202897Y160882D01*
G01X1203666Y161953D02*
X1200364Y163586D01*
G01X1183822Y165329D02*
X1199949Y162340D01*
G01X1193407Y155878D02*
X1187064Y160322D01*
G01X1194423Y156755D02*
X1187578Y161550D01*
G01X1196434Y149833D02*
X1193407Y155878D01*
G01X1197656Y150297D02*
X1194423Y156755D01*
G01X1197150Y147156D02*
X1196434Y149833D01*
G01X1198450Y147327D02*
X1197656Y150297D01*
G01X1197150Y145914D02*
Y147156D01*
G01X1198450Y145914D02*
Y147327D01*
G01X1190466Y151994D02*
X1183814Y156653D01*
G01X1191399Y152928D02*
X1184324Y157884D01*
G01X1191108Y151078D02*
X1190466Y151994D01*
G01X1192172Y151825D02*
X1191399Y152928D01*
G01X1192339Y151587D02*
X1192172Y151826D01*
G01X1191404Y149398D02*
X1191108Y151078D01*
G01X1192725Y149398D02*
X1192339Y151587D01*
G01X1191162Y148023D02*
X1191404Y149398D01*
G01X1192393Y147513D02*
X1192725Y149398D01*
G01X1188974Y144897D02*
X1191162Y148023D01*
G01X1190205Y144388D02*
X1192393Y147513D01*
G01X1188500Y142184D02*
X1188974Y144897D01*
G01X1189800Y142071D02*
X1190205Y144388D01*
G01X1214216Y170580D02*
X1205149Y176928D01*
G01X1215150Y171514D02*
X1205672Y178150D01*
G01X1193113Y173703D02*
X1185644Y172387D01*
G01X1193113Y175024D02*
X1185659Y173710D01*
G01X1205031Y171602D02*
X1193113Y173703D01*
G01X1205541Y172833D02*
X1193113Y175024D01*
G01X1211876Y166809D02*
X1205031Y171602D01*
G01X1212810Y167743D02*
X1205541Y172833D01*
G01X1209225Y164733D02*
X1208379Y165251D01*
G01X1209195Y163227D02*
X1207897Y164021D01*
G01X1210081Y164209D02*
X1209225Y164733D01*
G01X1209195Y163227D02*
X1207897Y164021D01*
G01X1212555Y160972D02*
X1210081Y164209D01*
G01X1211380Y160367D02*
X1209195Y163227D01*
G01X1183822Y165329D02*
X1199949Y162340D01*
G01X1203666Y161953D02*
X1200364Y163586D01*
G01X1199949Y162340D02*
X1202897Y160882D01*
G01X1206041Y159577D02*
X1203666Y161953D01*
G01X1202897Y160882D02*
X1204741Y159038D01*
G01X1206041Y157680D02*
Y159577D01*
G01X1204741Y159038D02*
Y157680D01*
G01X1194423Y156755D02*
X1187578Y161550D01*
G01X1193407Y155878D02*
X1187064Y160322D01*
G01X1197656Y150297D02*
X1194423Y156755D01*
G01X1196434Y149833D02*
X1193407Y155878D01*
G01X1198450Y147327D02*
X1197656Y150297D01*
G01X1197150Y147156D02*
X1196434Y149833D01*
G01X1198450Y145914D02*
Y147327D01*
G01X1197150Y145914D02*
Y147156D01*
G01X1191399Y152928D02*
X1184324Y157884D01*
G01X1190466Y151994D02*
X1183814Y156653D01*
G01X1192172Y151825D02*
X1191399Y152928D01*
G01X1191108Y151078D02*
X1190466Y151994D01*
G01X1192339Y151587D02*
X1192172Y151826D01*
G01X1191108Y151078D02*
X1190466Y151994D01*
G01X1192725Y149398D02*
X1192339Y151587D01*
G01X1191404Y149398D02*
X1191108Y151078D01*
G01X1192393Y147513D02*
X1192725Y149398D01*
G01X1191162Y148023D02*
X1191404Y149398D01*
G01X1190205Y144388D02*
X1192393Y147513D01*
G01X1188974Y144897D02*
X1191162Y148023D01*
G01X1189800Y142071D02*
X1190205Y144388D01*
G01X1188500Y142184D02*
X1188974Y144897D01*
G01X1193113Y175024D02*
X1185659Y173710D01*
G01X1193113Y173703D02*
X1185644Y172387D01*
G01X1205541Y172833D02*
X1193113Y175024D01*
G01X1205031Y171602D02*
X1193113Y173703D01*
G01X1212810Y167743D02*
X1205541Y172833D01*
G01X1211876Y166809D02*
X1205031Y171602D01*
G01X1179850Y144957D02*
X1178878Y145929D01*
G01X1181150Y145496D02*
X1179568Y147078D01*
G01X1179850Y144300D02*
Y144957D01*
G01X1181150Y144300D02*
Y145496D01*
G01D02*
X1179568Y147078D01*
G01X1179850Y144957D02*
X1178878Y145929D01*
G01X1181150Y144300D02*
Y145496D01*
G01X1179850Y144300D02*
Y144957D01*
G01X1184584Y197200D02*
X1214136Y191289D01*
G01X1214659Y192511D02*
X1184584Y198526D01*
G01X1211045Y188123D02*
X1186911Y192950D01*
G01Y194276D02*
X1211568Y189345D01*
G01X1208735Y184440D02*
X1188938Y188400D01*
G01X1209258Y185662D02*
X1188938Y189726D01*
G01X1219266Y177066D02*
X1208735Y184440D01*
G01X1220200Y178000D02*
X1209258Y185662D01*
G01X1206963Y180890D02*
X1216566Y174166D01*
G01X1207486Y182112D02*
X1217500Y175100D01*
G01X1191165Y184050D02*
X1206963Y180890D01*
G01X1191165Y185376D02*
X1207486Y182112D01*
G01X1178665Y181550D02*
X1191165Y184050D01*
G01X1178665Y182876D02*
X1191165Y185376D01*
G01X1214659Y192511D02*
X1184584Y198526D01*
G01Y197200D02*
X1214136Y191289D01*
G01X1186911Y194276D02*
X1211568Y189345D01*
G01X1211045Y188123D02*
X1186911Y192950D01*
G01X1209258Y185662D02*
X1188938Y189726D01*
G01X1208735Y184440D02*
X1188938Y188400D01*
G01X1220200Y178000D02*
X1209258Y185662D01*
G01X1219266Y177066D02*
X1208735Y184440D01*
G01X1207486Y182112D02*
X1217500Y175100D01*
G01X1206963Y180890D02*
X1216566Y174166D01*
G01X1191165Y185376D02*
X1207486Y182112D01*
G01X1191165Y184050D02*
X1206963Y180890D01*
G01X1178665Y182876D02*
X1191165Y185376D01*
G01X1178665Y181550D02*
X1191165Y184050D01*
G01X1193042Y180676D02*
X1181475Y178362D01*
G01X1193042Y179350D02*
X1181475Y177036D01*
G01X1205672Y178150D02*
X1193042Y180676D01*
G01X1205149Y176928D02*
X1193042Y179350D01*
G01D02*
X1181475Y177036D01*
G01X1193042Y180676D02*
X1181475Y178362D01*
G01X1205149Y176928D02*
X1193042Y179350D01*
G01X1205672Y178150D02*
X1193042Y180676D01*
G01X1185162Y616585D02*
X1276481Y747001D01*
G01X1186393Y616075D02*
X1277712Y746491D01*
G01X1195292Y623376D02*
X1309981Y787171D01*
G01X1196523Y622867D02*
X1311046Y786425D01*
G01X1186393Y616075D02*
X1277712Y746491D01*
G01X1185162Y616585D02*
X1276481Y747001D01*
G01X1195292Y623376D02*
X1309981Y787171D01*
G01X1196523Y622867D02*
X1311046Y786425D01*
G01X1195292Y623376D02*
X1309981Y787171D01*
G01X1199785Y620757D02*
X1320897Y793724D01*
G01X1201016Y620248D02*
X1322128Y793214D01*
G01X1203719Y620209D02*
X1335177Y807949D01*
G01X1204950Y619699D02*
X1336477Y807539D01*
G01X1347775Y819429D02*
X1207490Y619081D01*
G01X1349075Y819019D02*
X1208721Y618571D01*
G01X1201016Y620248D02*
X1322128Y793214D01*
G01X1199785Y620757D02*
X1320897Y793724D01*
G01X1204950Y619699D02*
X1336477Y807539D01*
G01X1203719Y620209D02*
X1335177Y807949D01*
G01X1349075Y819019D02*
X1208721Y618571D01*
G01X1347775Y819429D02*
X1207490Y619081D01*
G01X1186815Y744074D02*
X1193679Y783000D01*
G01X1188046Y743564D02*
X1191528Y763312D01*
G01X1186815Y744074D02*
X1193679Y783000D01*
G01X1188046Y743564D02*
X1191528Y763312D01*
G01X1186815Y744074D02*
X1193679Y783000D01*
G01X1178076Y804591D02*
X1182500Y779500D01*
G01X1191528Y763312D02*
X1195000Y783000D01*
G01X1178076Y804591D02*
X1182500Y779500D01*
G01X1191528Y763312D02*
X1195000Y783000D01*
G01X1180000Y815500D02*
X1178076Y804591D01*
G01X1177697Y821068D02*
X1178679Y815500D01*
G01X1178997Y821186D02*
X1180000Y815500D01*
G01X1189123Y808839D02*
X1191142Y820290D01*
G01X1190444Y808839D02*
X1192463Y820290D01*
G01X1193679Y783000D02*
X1189123Y808839D01*
G01X1195000Y783000D02*
X1190444Y808839D01*
G01X1180000Y815500D02*
X1178076Y804591D01*
G01X1178997Y821186D02*
X1180000Y815500D01*
G01X1177697Y821068D02*
X1178679Y815500D01*
G01X1190444Y808839D02*
X1192463Y820290D01*
G01X1189123Y808839D02*
X1191142Y820290D01*
G01X1195000Y783000D02*
X1190444Y808839D01*
G01X1193679Y783000D02*
X1189123Y808839D01*
G01X1177697Y828007D02*
Y821068D01*
G01X1178997Y828007D02*
Y821186D01*
G01X1190295Y825098D02*
Y828007D01*
G01X1191595Y825212D02*
Y828007D01*
G01X1191142Y820290D02*
X1190295Y825098D01*
G01X1192463Y820290D02*
X1191595Y825212D01*
G01X1178997Y828007D02*
Y821186D01*
G01X1177697Y828007D02*
Y821068D01*
G01X1191595Y825212D02*
Y828007D01*
G01X1190295Y825098D02*
Y828007D01*
G01X1192463Y820290D02*
X1191595Y825212D01*
G01X1191142Y820290D02*
X1190295Y825098D01*
G01X1241950Y139723D02*
Y142016D01*
G01X1240650Y140145D02*
Y141902D01*
G01X1223100Y140258D02*
Y141769D01*
G01X1224400Y139721D02*
Y141885D01*
G01X1240650Y140145D02*
Y141902D01*
G01X1241950Y139723D02*
Y142016D01*
G01X1224400Y139721D02*
Y141885D01*
G01X1223100Y140258D02*
Y141769D01*
G01X1232358Y174435D02*
X1245403Y165301D01*
G01X1245913Y166532D02*
X1233292Y175369D01*
G01X1226732Y182469D02*
X1232358Y174435D01*
G01X1233292Y175369D02*
X1227666Y183403D01*
G01X1228006Y172068D02*
X1222266Y180266D01*
G01X1223200Y181200D02*
X1228940Y173002D01*
G01X1241139Y162872D02*
X1228006Y172068D01*
G01X1228940Y173002D02*
X1241649Y164103D01*
G01X1268193Y158102D02*
X1241139Y162872D01*
G01X1241649Y164103D02*
X1268418Y159383D01*
G01X1225868Y167638D02*
X1219266Y177066D01*
G01X1226802Y168572D02*
X1220200Y178000D01*
G01X1235849Y160650D02*
X1225868Y167638D01*
G01X1236359Y161881D02*
X1226802Y168572D01*
G01X1257703Y156796D02*
X1235849Y160650D01*
G01X1258190Y158031D02*
X1236359Y161881D01*
G01X1233816Y157769D02*
X1250332Y154853D01*
G01X1234326Y159000D02*
X1250819Y156088D01*
G01X1222507Y165684D02*
X1233816Y157769D01*
G01X1223440Y166618D02*
X1234326Y159000D01*
G01X1216566Y174166D02*
X1222507Y165684D01*
G01X1217500Y175100D02*
X1223440Y166618D01*
G01X1233292Y175369D02*
X1227666Y183403D01*
G01X1226732Y182469D02*
X1232358Y174435D01*
G01X1245913Y166532D02*
X1233292Y175369D01*
G01X1232358Y174435D02*
X1245403Y165301D01*
G01X1241649Y164103D02*
X1268418Y159383D01*
G01X1268193Y158102D02*
X1241139Y162872D01*
G01X1228940Y173002D02*
X1241649Y164103D01*
G01X1241139Y162872D02*
X1228006Y172068D01*
G01X1223200Y181200D02*
X1228940Y173002D01*
G01X1228006Y172068D02*
X1222266Y180266D01*
G01X1226802Y168572D02*
X1220200Y178000D01*
G01X1225868Y167638D02*
X1219266Y177066D01*
G01X1236359Y161881D02*
X1226802Y168572D01*
G01X1235849Y160650D02*
X1225868Y167638D01*
G01X1258190Y158031D02*
X1236359Y161881D01*
G01X1257703Y156796D02*
X1235849Y160650D01*
G01X1234326Y159000D02*
X1250819Y156088D01*
G01X1233816Y157769D02*
X1250332Y154853D01*
G01X1223440Y166618D02*
X1234326Y159000D01*
G01X1222507Y165684D02*
X1233816Y157769D01*
G01X1217500Y175100D02*
X1223440Y166618D01*
G01X1216566Y174166D02*
X1222507Y165684D01*
G01X1221341Y162674D02*
X1215150Y171514D01*
G01X1220407Y161740D02*
X1214216Y170580D01*
G01X1236614Y151980D02*
X1221341Y162674D01*
G01X1235680Y151046D02*
X1220407Y161740D01*
G01X1241398Y145147D02*
X1236614Y151980D01*
G01X1240167Y144637D02*
X1235680Y151046D01*
G01X1241950Y142016D02*
X1241398Y145147D01*
G01X1240650Y141902D02*
X1240167Y144637D01*
G01X1213534Y153356D02*
X1211380Y160367D01*
G01X1214646Y154165D02*
X1212555Y160972D01*
G01X1218262Y150045D02*
X1213534Y153356D01*
G01X1219196Y150979D02*
X1214646Y154165D01*
G01X1222776Y143599D02*
X1218262Y150045D01*
G01X1224007Y144109D02*
X1219196Y150979D01*
G01X1223099Y141770D02*
X1222776Y143599D01*
G01X1224218Y142912D02*
X1224007Y144109D01*
G01X1224400Y141885D02*
X1224218Y142912D01*
G01X1220407Y161740D02*
X1214216Y170580D01*
G01X1221341Y162674D02*
X1215150Y171514D01*
G01X1235680Y151046D02*
X1220407Y161740D01*
G01X1236614Y151980D02*
X1221341Y162674D01*
G01X1240167Y144637D02*
X1235680Y151046D01*
G01X1241398Y145147D02*
X1236614Y151980D01*
G01X1240650Y141902D02*
X1240167Y144637D01*
G01X1241950Y142016D02*
X1241398Y145147D01*
G01X1216159Y160692D02*
X1211876Y166809D01*
G01X1217093Y161626D02*
X1212810Y167743D01*
G01X1225699Y154013D02*
X1216159Y160692D01*
G01X1226633Y154947D02*
X1217093Y161626D01*
G01X1231860Y145212D02*
X1225699Y154013D01*
G01X1233160Y145622D02*
X1226633Y154947D01*
G01X1231860Y144517D02*
Y145212D01*
G01X1233160Y144247D02*
Y145622D01*
G01X1214646Y154165D02*
X1212555Y160972D01*
G01X1213534Y153356D02*
X1211380Y160367D01*
G01X1219196Y150979D02*
X1214646Y154165D01*
G01X1218262Y150045D02*
X1213534Y153356D01*
G01X1224007Y144109D02*
X1219196Y150979D01*
G01X1222776Y143599D02*
X1218262Y150045D01*
G01X1224218Y142912D02*
X1224007Y144109D01*
G01X1223099Y141770D02*
X1222776Y143599D01*
G01X1224400Y141885D02*
X1224218Y142912D01*
G01X1223099Y141770D02*
X1222776Y143599D01*
G01X1217093Y161626D02*
X1212810Y167743D01*
G01X1216159Y160692D02*
X1211876Y166809D01*
G01X1226633Y154947D02*
X1217093Y161626D01*
G01X1225699Y154013D02*
X1216159Y160692D01*
G01X1233160Y145622D02*
X1226633Y154947D01*
G01X1231860Y145212D02*
X1225699Y154013D01*
G01X1233160Y144247D02*
Y145622D01*
G01X1231860Y144517D02*
Y145212D01*
G01X1214136Y191289D02*
X1226732Y182469D01*
G01X1227666Y183403D02*
X1214659Y192511D01*
G01X1222266Y180266D02*
X1211045Y188123D01*
G01X1211568Y189345D02*
X1223200Y181200D01*
G01X1227666Y183403D02*
X1214659Y192511D01*
G01X1214136Y191289D02*
X1226732Y182469D01*
G01X1211568Y189345D02*
X1223200Y181200D01*
G01X1222266Y180266D02*
X1211045Y188123D01*
G01X1215289Y753096D02*
X1223604Y800251D01*
G01X1216520Y752586D02*
X1224925Y800251D01*
G01X1216520Y752586D02*
X1224925Y800251D01*
G01X1215289Y753096D02*
X1223604Y800251D01*
G01X1227086Y753617D02*
X1235161Y799411D01*
G01X1228317Y753107D02*
X1236482Y799411D01*
G01X1228317Y753107D02*
X1236482Y799411D01*
G01X1227086Y753617D02*
X1235161Y799411D01*
G01X1221179Y814000D02*
X1222623Y822186D01*
G01X1222500Y814000D02*
X1223944Y822186D01*
G01X1223604Y800251D02*
X1221179Y814000D01*
G01X1224925Y800251D02*
X1222500Y814000D01*
G01D02*
X1223944Y822186D01*
G01X1221179Y814000D02*
X1222623Y822186D01*
G01X1224925Y800251D02*
X1222500Y814000D01*
G01X1223604Y800251D02*
X1221179Y814000D01*
G01X1232500Y814500D02*
X1234390Y825219D01*
G01X1233821Y814500D02*
X1235690Y825105D01*
G01X1235161Y799411D02*
X1232500Y814500D01*
G01X1236482Y799411D02*
X1233821Y814500D01*
G01D02*
X1235690Y825105D01*
G01X1232500Y814500D02*
X1234390Y825219D01*
G01X1236482Y799411D02*
X1233821Y814500D01*
G01X1235161Y799411D02*
X1232500Y814500D01*
G01X1221792Y826900D02*
Y828007D01*
G01X1223092Y827014D02*
Y828007D01*
G01X1222623Y822186D02*
X1221794Y826898D01*
G01X1223944Y822186D02*
X1223094Y827012D01*
G01X1223092Y827014D02*
Y828007D01*
G01X1221792Y826900D02*
Y828007D01*
G01X1223944Y822186D02*
X1223094Y827012D01*
G01X1222623Y822186D02*
X1221794Y826898D01*
G01X1234390Y825219D02*
Y828007D01*
G01X1235690Y825105D02*
Y828007D01*
G01Y825105D02*
Y828007D01*
G01X1234390Y825219D02*
Y828007D01*
G01X1274958Y141276D02*
X1262653Y153581D01*
G01X1274958Y139623D02*
Y141276D01*
G01X1276258Y139623D02*
Y141815D01*
G01X1274958Y141276D02*
X1262653Y153581D01*
G01X1276258Y139623D02*
Y141815D01*
G01X1274958Y139623D02*
Y141276D01*
G01X1270524Y160872D02*
X1287202Y149195D01*
G01X1288041Y150195D02*
X1271034Y162103D01*
G01X1245403Y165301D02*
X1270524Y160872D01*
G01X1271034Y162103D02*
X1245913Y166532D01*
G01X1268412Y158011D02*
G03X1268193Y158102I-315J-449D01*
G01X1268418Y159383D02*
G02X1269158Y159077I-320J-1821D01*
G01X1281785Y148644D02*
X1268412Y158011D01*
G01X1269158Y159077D02*
X1282738Y149564D01*
G01X1262653Y153581D02*
X1257703Y156796D01*
G01X1263476Y154597D02*
X1258190Y158031D01*
G01X1276258Y141815D02*
X1263476Y154597D01*
G01X1259653Y148360D02*
Y147351D01*
G01X1260953Y148899D02*
Y147351D01*
G01X1258395Y149618D02*
X1259653Y148360D01*
G01X1259218Y150634D02*
X1260953Y148899D01*
G01X1250332Y154853D02*
X1258395Y149618D01*
G01X1250819Y156088D02*
X1259218Y150634D01*
G01X1271034Y162103D02*
X1245913Y166532D01*
G01X1245403Y165301D02*
X1270524Y160872D01*
G01X1288041Y150195D02*
X1271034Y162103D01*
G01X1270524Y160872D02*
X1287202Y149195D01*
G01X1269158Y159077D02*
X1282738Y149564D01*
G01X1281785Y148644D02*
X1268412Y158011D01*
G01X1268418Y159383D02*
G02X1269158Y159077I-320J-1821D01*
G01X1268412Y158011D02*
G03X1268193Y158102I-315J-449D01*
G01X1263476Y154597D02*
X1258190Y158031D01*
G01X1262653Y153581D02*
X1257703Y156796D01*
G01X1276258Y141815D02*
X1263476Y154597D01*
G01X1260953Y148899D02*
Y147351D01*
G01X1259653Y148360D02*
Y147351D01*
G01X1259218Y150634D02*
X1260953Y148899D01*
G01X1258395Y149618D02*
X1259653Y148360D01*
G01X1250819Y156088D02*
X1259218Y150634D01*
G01X1250332Y154853D02*
X1258395Y149618D01*
G01X1274101Y791429D02*
X1266269Y747010D01*
G01X1275422Y791429D02*
X1267500Y746500D01*
G01X1276481Y747001D02*
X1286179Y802000D01*
G01X1277712Y746491D02*
X1285035Y788024D01*
G01X1275422Y791429D02*
X1267500Y746500D01*
G01X1274101Y791429D02*
X1266269Y747010D01*
G01X1276481Y747001D02*
X1286179Y802000D01*
G01X1276481Y747001D02*
X1286179Y802000D01*
G01X1277712Y746491D02*
X1285035Y788024D01*
G01X1276481Y747001D02*
X1286179Y802000D01*
G01X1250071Y791932D02*
X1245353Y765172D01*
G01X1251392Y791932D02*
X1246584Y764662D01*
G01X1267603Y787308D02*
X1262103Y756115D01*
G01X1263334Y755605D02*
X1268924Y787308D01*
G01X1251392Y791932D02*
X1246584Y764662D01*
G01X1250071Y791932D02*
X1245353Y765172D01*
G01X1263334Y755605D02*
X1268924Y787308D01*
G01X1267603D02*
X1262103Y756115D01*
G01X1246086Y814533D02*
X1250071Y791932D01*
G01X1247407Y814533D02*
X1251392Y791932D01*
G01X1247606Y823159D02*
X1246086Y814533D01*
G01X1247816Y816858D02*
X1247407Y814533D01*
G01X1266739Y792214D02*
X1267603Y787308D01*
G01X1268924D02*
X1268020Y792440D01*
G01X1265873Y797122D02*
X1266739Y792214D01*
G01X1267443Y795711D02*
X1267154Y797348D01*
G01X1268020Y792440D02*
X1267443Y795711D01*
G01X1265167Y801125D02*
X1265873Y797122D01*
G01X1267154Y797348D02*
X1266448Y801351D01*
G01X1264796Y803227D02*
X1265167Y801125D01*
G01X1266448Y801351D02*
X1265657Y805837D01*
G01X1264426Y805327D02*
X1264796Y803227D01*
G01X1266448Y801351D02*
X1265657Y805837D01*
G01X1259260Y812701D02*
X1264426Y805327D01*
G01X1265657Y805837D02*
X1260491Y813211D01*
G01X1258219Y818609D02*
X1259260Y812701D01*
G01X1260491Y813211D02*
X1259540Y818609D01*
G01X1270121Y814000D02*
X1274101Y791429D01*
G01X1271442Y814000D02*
X1275422Y791429D01*
G01X1272185Y825700D02*
X1270121Y814000D01*
G01X1273485Y825586D02*
X1271442Y814000D01*
G01X1247407Y814533D02*
X1251392Y791932D01*
G01X1246086Y814533D02*
X1250071Y791932D01*
G01X1247816Y816858D02*
X1247407Y814533D01*
G01X1247606Y823159D02*
X1246086Y814533D01*
G01X1247606Y823159D02*
X1246086Y814533D01*
G01X1260491Y813211D02*
X1259540Y818609D01*
G01X1258219D02*
X1259260Y812701D01*
G01X1265657Y805837D02*
X1260491Y813211D01*
G01X1259260Y812701D02*
X1264426Y805327D01*
G01X1266448Y801351D02*
X1265657Y805837D01*
G01X1264796Y803227D02*
X1265167Y801125D01*
G01X1264426Y805327D02*
X1264796Y803227D01*
G01X1267154Y797348D02*
X1266448Y801351D01*
G01X1265167Y801125D02*
X1265873Y797122D01*
G01X1267443Y795711D02*
X1267154Y797348D01*
G01X1265873Y797122D02*
X1266739Y792214D01*
G01X1268020Y792440D02*
X1267443Y795711D01*
G01X1265873Y797122D02*
X1266739Y792214D01*
G01X1268924Y787308D02*
X1268020Y792440D01*
G01X1266739Y792214D02*
X1267603Y787308D01*
G01X1271442Y814000D02*
X1275422Y791429D01*
G01X1270121Y814000D02*
X1274101Y791429D01*
G01X1273485Y825586D02*
X1271442Y814000D01*
G01X1272185Y825700D02*
X1270121Y814000D01*
G01X1248927Y823159D02*
X1247816Y816858D01*
G01X1246989Y826667D02*
X1247606Y823159D01*
G01X1248289Y826781D02*
X1248927Y823159D01*
G01X1246989Y828007D02*
Y826667D01*
G01X1248289Y828007D02*
Y826781D01*
G01X1259587Y826359D02*
X1258219Y818609D01*
G01X1259540D02*
X1260887Y826245D01*
G01X1259587Y828007D02*
Y826359D01*
G01X1260887Y826245D02*
Y828007D01*
G01X1272185D02*
Y825700D01*
G01X1273485Y828007D02*
Y825586D01*
G01X1248927Y823159D02*
X1247816Y816858D01*
G01X1248289Y826781D02*
X1248927Y823159D01*
G01X1246989Y826667D02*
X1247606Y823159D01*
G01X1248289Y828007D02*
Y826781D01*
G01X1246989Y828007D02*
Y826667D01*
G01X1260887Y826245D02*
Y828007D01*
G01X1259587D02*
Y826359D01*
G01X1259540Y818609D02*
X1260887Y826245D01*
G01X1259587Y826359D02*
X1258219Y818609D01*
G01X1273485Y828007D02*
Y825586D01*
G01X1272185Y828007D02*
Y825700D01*
G01X1293849Y142548D02*
Y139353D01*
G01X1295149D02*
Y143087D01*
G01Y139353D02*
Y143087D01*
G01X1293849Y142548D02*
Y139353D01*
G01X1287202Y149195D02*
X1293849Y142548D01*
G01X1295149Y143087D02*
X1288041Y150195D01*
G01X1284188Y144945D02*
X1281785Y148644D01*
G01X1282738Y149564D02*
X1285488Y145331D01*
G01X1284188Y143621D02*
Y144945D01*
G01X1285488Y145331D02*
Y143750D01*
G01X1295149Y143087D02*
X1288041Y150195D01*
G01X1287202Y149195D02*
X1293849Y142548D01*
G01X1285488Y145331D02*
Y143750D01*
G01X1284188Y143621D02*
Y144945D01*
G01X1282738Y149564D02*
X1285488Y145331D01*
G01X1284188Y144945D02*
X1281785Y148644D01*
G01X1286179Y802000D02*
X1283430Y817590D01*
G01X1287500Y802000D02*
X1284751Y817590D01*
G01X1287461Y801775D02*
X1287500Y802000D01*
G01X1285035Y788024D02*
X1287460Y801775D01*
G01X1308679Y806500D02*
X1310892Y819051D01*
G01X1310000Y806500D02*
X1312213Y819051D01*
G01X1311346Y791376D02*
X1308679Y806500D01*
G01X1312682Y791288D02*
X1310000Y806500D01*
G01X1310177Y787687D02*
X1311346Y791376D01*
G01X1311417Y787294D02*
X1312682Y791288D01*
G01X1311047Y786425D02*
X1311281Y786759D01*
G01X1287500Y802000D02*
X1284751Y817590D01*
G01X1286179Y802000D02*
X1283430Y817590D01*
G01X1287461Y801775D02*
X1287500Y802000D01*
G01X1285035Y788024D02*
X1287460Y801775D01*
G01X1310000Y806500D02*
X1312213Y819051D01*
G01X1308679Y806500D02*
X1310892Y819051D01*
G01X1312682Y791288D02*
X1310000Y806500D01*
G01X1311346Y791376D02*
X1308679Y806500D01*
G01X1311417Y787294D02*
X1312682Y791288D01*
G01X1310177Y787687D02*
X1311346Y791376D01*
G01X1311047Y786425D02*
X1311281Y786759D01*
G01X1284783Y825262D02*
Y828007D01*
G01X1286083Y825145D02*
Y828007D01*
G01X1283430Y817590D02*
X1284783Y825262D01*
G01X1284751Y817590D02*
X1286083Y825145D01*
G01X1309981Y824219D02*
Y828007D01*
G01X1311281Y824337D02*
Y828007D01*
G01X1310892Y819051D02*
X1309981Y824219D01*
G01X1312213Y819051D02*
X1311281Y824337D01*
G01X1286083Y825145D02*
Y828007D01*
G01X1284783Y825262D02*
Y828007D01*
G01X1284751Y817590D02*
X1286083Y825145D01*
G01X1283430Y817590D02*
X1284783Y825262D01*
G01X1311281Y824337D02*
Y828007D01*
G01X1309981Y824219D02*
Y828007D01*
G01X1312213Y819051D02*
X1311281Y824337D01*
G01X1310892Y819051D02*
X1309981Y824219D01*
G01X1322579Y803261D02*
Y828007D01*
G01X1323879Y803143D02*
Y828007D01*
G01X1323860Y803036D02*
Y803035D01*
G01X1320897Y793724D02*
X1322579Y803261D01*
G01X1323860Y803035D02*
X1323879Y803143D01*
G01X1323019Y798267D02*
X1323860Y803036D01*
G01X1322128Y793214D02*
X1323019Y798267D01*
G01X1335177Y807949D02*
Y828007D01*
G01X1336477Y807539D02*
Y828007D01*
G01X1323879Y803143D02*
Y828007D01*
G01X1322579Y803261D02*
Y828007D01*
G01X1323860Y803035D02*
X1323879Y803143D01*
G01X1320897Y793724D02*
X1322579Y803261D01*
G01X1323860Y803036D02*
Y803035D01*
G01X1322579Y803261D02*
Y828007D01*
G01X1323019Y798267D02*
X1323860Y803036D01*
G01X1320897Y793724D02*
X1322579Y803261D01*
G01X1322128Y793214D02*
X1323019Y798267D01*
G01X1320897Y793724D02*
X1322579Y803261D01*
G01X1336477Y807539D02*
Y828007D01*
G01X1335177Y807949D02*
Y828007D01*
G01X1347775Y828700D02*
Y819429D01*
G01X1349075Y828700D02*
Y819019D01*
G01Y828700D02*
Y819019D01*
G01X1347775Y828700D02*
Y819429D01*
M02*
